%FSTAX23Y23*%
%MOIN*%
%SFA1B1*%

%IPPOS*%
%ADD10C,0.009840*%
%ADD11C,0.023620*%
%ADD12C,0.003940*%
%ADD13C,0.010000*%
%ADD14C,0.007870*%
%ADD15C,0.015750*%
%ADD16C,0.015750*%
%ADD17C,0.006000*%
%ADD18C,0.004720*%
%ADD19C,0.008000*%
%ADD20C,0.007000*%
%ADD21C,0.005000*%
%ADD22C,0.005910*%
%ADD23C,0.007990*%
%ADD24C,0.009000*%
%ADD25R,0.025000X0.010000*%
%LNgrandmaster-1*%
%LPD*%
G36*
X01297Y04157D02*
X01297D01*
X01298Y04157*
X01298Y04157*
X01298Y04157*
X01299Y04157*
X01299Y04157*
X013Y04157*
X013Y04157*
X01301Y04157*
X01301Y04157*
X01302Y04157*
X01302Y04156*
X01302Y04156*
X01302Y04156*
X01302Y04156*
X01303Y04156*
X01303Y04156*
X01303Y04156*
X01303Y04156*
X01303Y04156*
X01304Y04156*
X01304Y04156*
X01304Y04155*
X01304Y04155*
X01305Y04155*
X01305Y04155*
X01305Y04155*
X01305Y04154*
X01305Y04154*
X01305Y04154*
X01305Y04154*
X01306Y04154*
X01306Y04154*
X01306Y04154*
X01306Y04154*
X01306Y04153*
X01306Y04153*
X01306Y04153*
X01306Y04153*
X01306Y04152*
X01306Y04152*
X01306Y04152*
X01306Y04151*
X01306Y04151*
Y04151*
X01306Y04151*
X01306Y0415*
X01306Y0415*
X01306Y0415*
X01306Y0415*
X01306Y04149*
X01306Y04149*
X01306Y04149*
X01306Y04148*
X01306Y04148*
X01305Y04148*
X01305Y04147*
X01305Y04147*
X01305Y04147*
X01305*
X01305Y04147*
X01304Y04147*
X01304Y04146*
X01304Y04146*
X01304Y04146*
X01304Y04146*
X01304Y04146*
X01304Y04146*
X01304Y04146*
X01304Y04146*
X01303Y04146*
X01303Y04146*
X01303Y04146*
X01303Y04146*
X01303Y04146*
X01302Y04146*
X01302Y04145*
X01302Y04145*
X01302Y04145*
X01301Y04145*
X01301Y04145*
X01301Y04145*
X013Y04145*
X013Y04145*
X01299Y04145*
X01299Y04145*
X01299Y04145*
X01298Y04145*
X01298Y04145*
X01297Y04145*
X01297*
X01297*
X01297*
X01297*
X01297*
X01297*
X01296*
X01296Y04145*
X01296*
X01296Y04145*
X01296Y04145*
X01295Y04145*
X01295Y04145*
X01294Y04145*
X01294Y04145*
X01293Y04145*
X01293Y04145*
X01292Y04145*
X01292Y04145*
X01291Y04145*
X01291Y04145*
X01291Y04145*
X01291Y04145*
X01291Y04145*
X01291Y04146*
X01291Y04146*
X0129Y04146*
X0129Y04146*
X0129Y04146*
X0129Y04146*
X01289Y04146*
X01289Y04147*
X01289Y04147*
X01289Y04147*
X01288Y04147*
X01288Y04147*
X01288Y04147*
X01288Y04148*
X01288Y04148*
X01288Y04148*
X01288Y04148*
X01288Y04148*
X01288Y04148*
X01288Y04148*
X01287Y04149*
X01287Y04149*
X01287Y04149*
X01287Y04149*
X01287Y0415*
X01287Y0415*
X01287Y04151*
X01287Y04151*
Y04151*
X01287Y04151*
Y04151*
X01287Y04151*
X01287Y04152*
X01287Y04152*
X01287Y04152*
X01287Y04153*
X01287Y04153*
X01288Y04153*
X01288Y04154*
Y04154*
X01288Y04154*
X01288Y04154*
X01288Y04154*
X01288Y04154*
X01288Y04154*
X01288Y04154*
X01288Y04154*
X01288Y04155*
X01289Y04155*
X01289Y04155*
X01289Y04155*
X01289Y04156*
X01289Y04156*
X0129Y04156*
X0129Y04156*
X0129Y04156*
X0129Y04156*
X0129Y04156*
X0129Y04156*
X0129Y04156*
X01291Y04156*
X01291Y04156*
X01291Y04156*
X01291Y04156*
X01292Y04157*
X01292Y04157*
X01292Y04157*
X01292*
X01292Y04157*
X01292Y04157*
X01293Y04157*
X01293Y04157*
X01293Y04157*
X01293Y04157*
X01293Y04157*
X01294Y04157*
X01294Y04157*
X01294Y04157*
X01295Y04157*
X01295Y04157*
X01296Y04157*
X01296Y04157*
X01297*
X01297*
X01297*
X01297*
X01297*
X01297*
X01297*
X01297Y04157*
G37*
G36*
X01306Y04136D02*
X01291D01*
X01291Y04136*
X01291Y04136*
X01291Y04136*
X01291Y04136*
X01291Y04136*
X01292Y04136*
X01292Y04136*
X01292Y04136*
X01292Y04136*
X01292Y04135*
X01292Y04135*
X01292Y04135*
X01292Y04135*
X01293Y04135*
X01293Y04134*
X01293Y04134*
X01293Y04134*
X01293Y04134*
X01293Y04134*
X01293Y04134*
X01293Y04134*
X01293Y04133*
X01293Y04133*
X01294Y04133*
X01294Y04132*
X01294Y04132*
X01294Y04132*
X01292*
X01292Y04132*
X01292Y04132*
X01292Y04132*
X01292Y04132*
X01292Y04132*
X01291Y04132*
X01291Y04133*
X01291Y04133*
X01291Y04133*
X01291Y04133*
X0129Y04134*
X0129Y04135*
X0129Y04135*
X0129Y04135*
X0129Y04135*
X01289Y04135*
X01289Y04135*
X01289Y04135*
X01289Y04136*
X01289Y04136*
X01289Y04136*
X01289Y04136*
X01288Y04136*
X01288Y04137*
X01287Y04137*
X01287Y04137*
X01287Y04137*
Y04139*
X01306*
Y04136*
G37*
G36*
Y04125D02*
X01302Y04123D01*
X01302Y04123*
X01302Y04123*
X01302Y04123*
X01302Y04122*
X01302Y04122*
X01302Y04122*
X01301Y04122*
X01301Y04122*
X01301Y04122*
X013Y04121*
X013Y04121*
X013Y04121*
X013Y04121*
X013Y04121*
X013Y04121*
X01299Y04121*
X01299Y04121*
X01299Y04121*
X01299Y0412*
X01299Y0412*
X01299Y0412*
X01298Y0412*
X01298Y0412*
X01298Y0412*
X01298Y04119*
X01298Y04119*
X01298Y04119*
X01298Y04119*
X01298Y04119*
X01298Y04119*
X01298Y04118*
Y04118*
X01298Y04118*
X01298Y04118*
X01298Y04118*
X01298Y04118*
X01298Y04118*
X01298Y04117*
Y04114*
X01306*
Y04112*
X01287*
Y0412*
X01287Y0412*
Y04121*
X01287Y04121*
X01287Y04121*
X01287Y04121*
X01287Y04122*
X01287Y04122*
X01287Y04123*
X01287Y04123*
X01287Y04123*
X01288Y04124*
X01288Y04124*
Y04124*
X01288Y04124*
X01288Y04124*
X01288Y04124*
X01288Y04124*
X01288Y04124*
X01288Y04125*
X01288Y04125*
X01288Y04125*
X01288Y04125*
X01288Y04125*
X01289Y04125*
X01289Y04126*
X01289Y04126*
X01289Y04126*
X01289Y04126*
X01289Y04126*
X01289Y04126*
X0129Y04126*
X0129Y04126*
X0129Y04126*
X0129Y04126*
X0129Y04126*
X0129Y04126*
X0129Y04127*
X01291Y04127*
X01291Y04127*
X01291Y04127*
X01291Y04127*
X01292Y04127*
X01292Y04127*
X01292Y04127*
X01292*
X01292*
X01292Y04127*
X01293*
X01293Y04127*
X01293Y04127*
X01293Y04127*
X01293Y04127*
X01294Y04127*
X01294Y04127*
X01294Y04126*
X01295Y04126*
X01295Y04126*
X01295Y04126*
X01295Y04126*
X01296Y04126*
X01296Y04125*
X01296Y04125*
X01296Y04125*
X01296Y04125*
X01296Y04125*
X01296Y04125*
X01296Y04125*
X01296Y04125*
X01297Y04124*
X01297Y04124*
X01297Y04124*
X01297Y04123*
X01297Y04123*
X01297Y04122*
X01297Y04122*
X01297Y04121*
Y04121*
X01298Y04121*
X01298Y04122*
X01298Y04122*
X01298Y04122*
X01298Y04122*
X01298Y04122*
X01298Y04122*
X01298Y04123*
X01298Y04123*
X01298Y04123*
X01298Y04123*
X01298Y04123*
X01299Y04123*
X01299Y04123*
X01299Y04123*
X01299Y04123*
X01299Y04124*
X01299Y04124*
X01299Y04124*
X013Y04124*
X013Y04124*
X013Y04124*
X013Y04125*
X013Y04125*
X01301Y04125*
X01306Y04128*
Y04125*
G37*
G36*
X01309Y04041D02*
X01294D01*
X01294Y04041*
X01294Y04041*
X01294Y04041*
X01294Y04041*
X01295Y04041*
X01295Y0404*
X01295Y0404*
X01295Y0404*
X01295Y0404*
X01295Y0404*
X01295Y0404*
X01295Y04039*
X01296Y04039*
X01296Y04039*
X01296Y04039*
X01296Y04039*
X01296Y04038*
X01296Y04038*
X01296Y04038*
X01296Y04038*
X01296Y04038*
X01296Y04038*
X01296Y04038*
X01297Y04037*
X01297Y04037*
X01297Y04036*
X01297Y04036*
X01295*
X01295Y04036*
X01295Y04036*
X01295Y04036*
X01295Y04036*
X01295Y04037*
X01295Y04037*
X01294Y04037*
X01294Y04037*
X01294Y04037*
X01294Y04038*
X01294Y04038*
X01293Y04039*
X01293Y0404*
X01293Y0404*
X01293Y0404*
X01293Y0404*
X01292Y0404*
X01292Y0404*
X01292Y0404*
X01292Y0404*
X01292Y0404*
X01292Y0404*
X01291Y04041*
X01291Y04041*
X01291Y04041*
X0129Y04041*
X0129Y04042*
Y04043*
X01309*
Y04041*
G37*
G36*
Y04026D02*
X01294D01*
X01294Y04026*
X01294Y04026*
X01294Y04026*
X01294Y04026*
X01295Y04026*
X01295Y04026*
X01295Y04025*
X01295Y04025*
X01295Y04025*
X01295Y04025*
X01295Y04025*
X01295Y04025*
X01296Y04024*
X01296Y04024*
X01296Y04024*
X01296Y04024*
X01296Y04024*
X01296Y04024*
X01296Y04023*
X01296Y04023*
X01296Y04023*
X01296Y04023*
X01296Y04023*
X01297Y04022*
X01297Y04022*
X01297Y04022*
X01297Y04021*
X01295*
X01295Y04021*
X01295Y04021*
X01295Y04021*
X01295Y04022*
X01295Y04022*
X01295Y04022*
X01294Y04022*
X01294Y04022*
X01294Y04023*
X01294Y04023*
X01294Y04024*
X01293Y04024*
X01293Y04025*
X01293Y04025*
X01293Y04025*
X01293Y04025*
X01292Y04025*
X01292Y04025*
X01292Y04025*
X01292Y04025*
X01292Y04025*
X01292Y04026*
X01291Y04026*
X01291Y04026*
X01291Y04026*
X0129Y04027*
X0129Y04027*
Y04028*
X01309*
Y04026*
G37*
G36*
Y04015D02*
X01305Y04012D01*
X01305Y04012*
X01305Y04012*
X01305Y04012*
X01305Y04012*
X01305Y04012*
X01305Y04012*
X01305Y04012*
X01304Y04012*
X01304Y04011*
X01303Y04011*
X01303Y04011*
X01303Y04011*
X01303Y0401*
X01303Y0401*
X01303Y0401*
X01303Y0401*
X01303Y0401*
X01302Y0401*
X01302Y0401*
X01302Y0401*
X01302Y0401*
X01302Y04009*
X01301Y04009*
X01301Y04009*
X01301Y04009*
X01301Y04009*
X01301Y04009*
X01301Y04009*
X01301Y04008*
X01301Y04008*
X01301Y04008*
Y04008*
X01301Y04008*
X01301Y04008*
X01301Y04008*
X01301Y04008*
X01301Y04007*
X01301Y04007*
Y04004*
X01309*
Y04001*
X0129*
Y0401*
X0129Y0401*
Y0401*
X0129Y04011*
X0129Y04011*
X0129Y04011*
X0129Y04011*
X0129Y04012*
X0129Y04012*
X0129Y04013*
X01291Y04013*
X01291Y04013*
X01291Y04014*
Y04014*
X01291Y04014*
X01291Y04014*
X01291Y04014*
X01291Y04014*
X01291Y04014*
X01291Y04014*
X01291Y04014*
X01291Y04014*
X01291Y04015*
X01292Y04015*
X01292Y04015*
X01292Y04015*
X01292Y04015*
X01292Y04015*
X01293Y04016*
X01293Y04016*
X01293Y04016*
X01293Y04016*
X01293Y04016*
X01293Y04016*
X01293Y04016*
X01293Y04016*
X01293Y04016*
X01294Y04016*
X01294Y04016*
X01294Y04016*
X01294Y04016*
X01295Y04016*
X01295Y04016*
X01295Y04016*
X01295Y04016*
X01295*
X01295*
X01296Y04016*
X01296*
X01296Y04016*
X01296Y04016*
X01296Y04016*
X01297Y04016*
X01297Y04016*
X01297Y04016*
X01297Y04016*
X01298Y04016*
X01298Y04016*
X01298Y04016*
X01299Y04015*
X01299Y04015*
X01299Y04015*
X01299Y04015*
X01299Y04015*
X01299Y04015*
X01299Y04015*
X01299Y04015*
X01299Y04014*
X013Y04014*
X013Y04014*
X013Y04014*
X013Y04013*
X013Y04013*
X013Y04012*
X013Y04012*
X01301Y04012*
X01301Y04011*
Y04011*
X01301Y04011*
X01301Y04011*
X01301Y04011*
X01301Y04011*
X01301Y04011*
X01301Y04012*
X01301Y04012*
X01301Y04012*
X01301Y04012*
X01302Y04013*
X01302Y04013*
X01302Y04013*
X01302Y04013*
X01302Y04013*
X01302Y04013*
X01302Y04013*
X01302Y04013*
X01302Y04013*
X01302Y04013*
X01303Y04014*
X01303Y04014*
X01303Y04014*
X01303Y04014*
X01304Y04014*
X01304Y04015*
X01309Y04018*
Y04015*
G37*
G36*
X02159Y03943D02*
X02159Y03942D01*
Y03942*
X02159Y03942*
X02159Y03942*
X02159Y03941*
X02159Y03941*
X02159Y03941*
X02158Y0394*
X02158Y0394*
X02158Y0394*
X02158Y03939*
X02158Y03939*
Y03939*
X02158Y03939*
X02158Y03939*
X02158Y03939*
X02158Y03939*
X02158Y03939*
X02158Y03938*
X02158Y03938*
X02158Y03938*
X02157Y03938*
X02157Y03938*
X02157Y03938*
X02157Y03937*
X02157Y03937*
X02157Y03937*
X02156Y03937*
X02156Y03937*
X02156Y03937*
X02156Y03937*
X02156Y03937*
X02156Y03937*
X02156Y03937*
X02156Y03937*
X02155Y03936*
X02155Y03936*
X02155Y03936*
X02155Y03936*
X02155Y03936*
X02154Y03936*
X02154Y03936*
X02154Y03936*
X02153Y03936*
X02153*
X02153*
X02153Y03936*
X02153*
X02153Y03936*
X02153Y03936*
X02152Y03936*
X02152Y03936*
X02152Y03936*
X02152Y03936*
X02151Y03937*
X02151Y03937*
X02151Y03937*
X02151Y03937*
X0215Y03937*
X0215Y03937*
X0215Y03937*
X0215Y03937*
X0215Y03938*
X0215Y03938*
X0215Y03938*
X0215Y03938*
X02149Y03938*
X02149Y03938*
X02149Y03939*
X02149Y03939*
X02149Y03939*
X02149Y0394*
X02149Y0394*
X02148Y03941*
X02148Y03941*
X02148Y03941*
Y03941*
X02148Y03941*
X02148Y03941*
X02148Y03941*
X02148Y03941*
X02148Y03941*
X02148Y03941*
X02148Y03941*
X02148Y0394*
X02147Y0394*
X02147Y0394*
X02147Y0394*
X02147Y0394*
X02147Y0394*
X02147Y0394*
X02147Y0394*
X02147Y0394*
X02147Y03939*
X02147Y03939*
X02146Y03939*
X02146Y03939*
X02146Y03939*
X02146Y03939*
X02146Y03938*
X02145Y03938*
X02145Y03938*
X0214Y03935*
Y03938*
X02144Y0394*
X02144Y0394*
X02144Y0394*
X02144Y0394*
X02144Y0394*
X02144Y03941*
X02144Y03941*
X02144Y03941*
X02144Y03941*
X02145Y03941*
X02145Y03941*
X02146Y03942*
X02146Y03942*
X02146Y03942*
X02146Y03942*
X02146Y03942*
X02146Y03942*
X02146Y03942*
X02146Y03942*
X02147Y03942*
X02147Y03943*
X02147Y03943*
X02147Y03943*
X02147Y03943*
X02147Y03943*
X02147Y03943*
X02148Y03944*
X02148Y03944*
X02148Y03944*
X02148Y03944*
X02148Y03944*
X02148Y03944*
Y03945*
X02148Y03945*
X02148Y03945*
X02148Y03945*
X02148Y03945*
X02148Y03945*
X02148Y03946*
Y03949*
X0214*
Y03951*
X02159*
Y03943*
G37*
G36*
X02154Y03931D02*
X02154Y03931D01*
X02154Y03931*
X02154Y03931*
X02154Y03931*
X02154Y03931*
X02154Y0393*
X02155Y0393*
X02155Y0393*
X02155Y0393*
X02155Y03929*
X02156Y03928*
X02156Y03928*
X02156Y03928*
X02156Y03928*
X02156Y03928*
X02156Y03928*
X02156Y03927*
X02157Y03927*
X02157Y03927*
X02157Y03927*
X02157Y03927*
X02157Y03927*
X02158Y03926*
X02158Y03926*
X02158Y03926*
X02159Y03926*
Y03924*
X0214*
Y03927*
X02154*
X02154Y03927*
X02154Y03927*
X02154Y03927*
X02154Y03927*
X02154Y03927*
X02154Y03927*
X02154Y03927*
X02154Y03927*
X02154Y03927*
X02154Y03928*
X02154Y03928*
X02153Y03928*
X02153Y03928*
X02153Y03928*
X02153Y03929*
X02153Y03929*
X02153Y03929*
X02153Y03929*
X02153Y03929*
X02153Y03929*
X02153Y03929*
X02152Y03929*
X02152Y0393*
X02152Y0393*
X02152Y0393*
X02152Y03931*
X02152Y03931*
X02154*
X02154Y03931*
G37*
G36*
X0214Y03919D02*
X0214Y03919D01*
X0214Y03918*
X02141Y03918*
X02141Y03918*
X02141Y03918*
X02141*
X02141Y03918*
X02141Y03918*
X02141Y03918*
X02141Y03918*
X02142Y03918*
X02142Y03918*
X02142Y03918*
X02142Y03918*
X02142Y03918*
X02143Y03917*
X02143Y03917*
X02144Y03917*
X02144Y03917*
X02144Y03917*
X02144Y03917*
X02144Y03917*
X02144Y03916*
X02144Y03916*
X02144Y03916*
X02145Y03916*
X02145Y03916*
X02145Y03916*
X02145Y03915*
X02145Y03915*
X02146Y03915*
X02146Y03914*
X02146Y03914*
X02147Y03914*
X02147Y03914*
X02147Y03914*
X02147Y03914*
X02147Y03914*
X02147Y03913*
X02147Y03913*
X02147Y03913*
X02147Y03913*
X02147Y03913*
X02148Y03912*
X02148Y03912*
X02148Y03912*
X02149Y03911*
X02149Y03911*
X02149Y03911*
X0215Y0391*
X0215Y0391*
X0215Y0391*
X02151Y03909*
X02151Y03909*
X02151Y03909*
X02151Y03909*
X02151Y03909*
X02151Y03909*
X02151Y03909*
X02151Y03909*
X02152Y03909*
X02152Y03909*
X02152Y03909*
X02152Y03909*
X02153Y03908*
X02153Y03908*
X02153Y03908*
X02153Y03908*
X02153*
X02154*
X02154*
X02154Y03908*
X02154Y03908*
X02154Y03908*
X02154Y03908*
X02154Y03908*
X02154Y03909*
X02155Y03909*
X02155Y03909*
X02155Y03909*
X02155Y03909*
X02155Y03909*
X02156Y03909*
X02156Y03909*
X02156Y03909*
X02156Y03909*
X02156Y03909*
X02156Y0391*
X02156Y0391*
X02156Y0391*
X02156Y0391*
X02156Y0391*
X02156Y0391*
X02156Y0391*
X02157Y03911*
X02157Y03911*
X02157Y03911*
X02157Y03911*
X02157Y03912*
X02157Y03912*
Y03912*
X02157Y03912*
X02157Y03912*
X02157Y03913*
X02157Y03913*
X02157Y03913*
X02157Y03913*
X02157Y03913*
X02156Y03914*
X02156Y03914*
X02156Y03914*
X02156Y03914*
X02156Y03914*
X02156Y03915*
X02156Y03915*
X02156Y03915*
X02156Y03915*
X02156Y03915*
X02155Y03915*
X02155Y03915*
X02155Y03915*
X02155Y03915*
X02155Y03915*
X02155Y03915*
X02154Y03915*
X02154Y03916*
X02154Y03916*
X02154Y03916*
X02153Y03916*
X02153Y03916*
X02153Y03918*
X02153*
X02153*
X02153Y03918*
X02153*
X02153Y03918*
X02154Y03918*
X02154Y03918*
X02154Y03918*
X02154Y03918*
X02155Y03918*
X02155Y03918*
X02155Y03918*
X02156Y03917*
X02156Y03917*
X02156Y03917*
X02157Y03917*
X02157Y03917*
X02157Y03916*
X02157Y03916*
X02157Y03916*
X02157Y03916*
X02157Y03916*
X02158Y03916*
X02158Y03916*
X02158Y03915*
X02158Y03915*
X02158Y03915*
X02158Y03914*
X02158Y03914*
X02158Y03914*
X02159Y03913*
X02159Y03913*
X02159Y03912*
X02159Y03912*
Y03912*
X02159Y03912*
X02159Y03911*
X02159Y03911*
X02159Y03911*
X02159Y03911*
X02159Y0391*
X02158Y0391*
X02158Y0391*
X02158Y03909*
X02158Y03909*
X02158Y03909*
X02158Y03908*
X02157Y03908*
X02157Y03908*
X02157Y03908*
X02157Y03907*
X02157Y03907*
X02157Y03907*
X02157Y03907*
X02157Y03907*
X02156Y03907*
X02156Y03907*
X02156Y03907*
X02156Y03906*
X02155Y03906*
X02155Y03906*
X02155Y03906*
X02154Y03906*
X02154Y03906*
X02153Y03906*
X02153*
X02153*
X02153*
X02153*
X02153Y03906*
X02153Y03906*
X02153Y03906*
X02153Y03906*
X02152Y03906*
X02152Y03906*
X02152Y03906*
X02151Y03906*
X02151*
X02151Y03906*
X02151Y03906*
X02151Y03907*
X02151Y03907*
X02151Y03907*
X02151Y03907*
X0215Y03907*
X0215Y03907*
X0215Y03907*
X0215Y03907*
X02149Y03907*
X02149Y03908*
X02149Y03908*
X02149Y03908*
X02149Y03908*
X02149Y03908*
X02149Y03908*
X02149Y03908*
X02148Y03908*
X02148Y03908*
X02148Y03909*
X02148Y03909*
X02148Y03909*
X02147Y03909*
X02147Y0391*
X02147Y0391*
X02147Y0391*
X02146Y03911*
X02146Y03911*
X02145Y03912*
X02145Y03912*
X02145Y03912*
X02145Y03912*
X02145Y03912*
X02145Y03912*
X02145Y03912*
X02145Y03912*
X02144Y03913*
X02144Y03913*
X02144Y03913*
X02144Y03914*
X02143Y03914*
X02143Y03914*
X02143Y03914*
X02143Y03914*
X02143Y03914*
X02143Y03914*
X02143Y03915*
X02143Y03915*
X02142Y03915*
X02142Y03915*
X02142Y03915*
X02142Y03915*
Y03906*
X0214*
Y03919*
X0214*
X0214*
X0214*
X0214*
X0214*
X0214Y03919*
G37*
G36*
X02221Y03944D02*
X02221Y03944D01*
Y03943*
X02221Y03943*
X02221Y03943*
X02221Y03943*
X02221Y03942*
X02221Y03942*
X02221Y03941*
X02221Y03941*
X0222Y03941*
X0222Y0394*
X0222Y0394*
Y0394*
X0222Y0394*
X0222Y0394*
X0222Y0394*
X0222Y0394*
X0222Y0394*
X0222Y03939*
X0222Y03939*
X0222Y03939*
X0222Y03939*
X02219Y03939*
X02219Y03939*
X02219Y03938*
X02219Y03938*
X02219Y03938*
X02218Y03938*
X02218Y03938*
X02218Y03938*
X02218Y03938*
X02218Y03938*
X02218Y03938*
X02218Y03938*
X02218Y03938*
X02218Y03938*
X02217Y03938*
X02217Y03937*
X02217Y03937*
X02217Y03937*
X02216Y03937*
X02216Y03937*
X02216Y03937*
X02216Y03937*
X02216*
X02216*
X02215Y03937*
X02215*
X02215Y03937*
X02215Y03937*
X02215Y03937*
X02214Y03937*
X02214Y03937*
X02214Y03937*
X02214Y03938*
X02213Y03938*
X02213Y03938*
X02213Y03938*
X02212Y03938*
X02212Y03938*
X02212Y03939*
X02212Y03939*
X02212Y03939*
X02212Y03939*
X02212Y03939*
X02212Y03939*
X02212Y03939*
X02211Y03939*
X02211Y0394*
X02211Y0394*
X02211Y0394*
X02211Y03941*
X02211Y03941*
X02211Y03942*
X0221Y03942*
X0221Y03943*
Y03943*
X0221Y03943*
X0221Y03942*
X0221Y03942*
X0221Y03942*
X0221Y03942*
X0221Y03942*
X0221Y03942*
X0221Y03941*
X0221Y03941*
X02209Y03941*
X02209Y03941*
X02209Y03941*
X02209Y03941*
X02209Y03941*
X02209Y03941*
X02209Y03941*
X02209Y0394*
X02209Y0394*
X02209Y0394*
X02208Y0394*
X02208Y0394*
X02208Y0394*
X02208Y0394*
X02207Y03939*
X02207Y03939*
X02202Y03936*
Y03939*
X02206Y03941*
X02206Y03941*
X02206Y03941*
X02206Y03941*
X02206Y03942*
X02206Y03942*
X02206Y03942*
X02206Y03942*
X02207Y03942*
X02207Y03942*
X02208Y03943*
X02208Y03943*
X02208Y03943*
X02208Y03943*
X02208Y03943*
X02208Y03943*
X02208Y03943*
X02208Y03943*
X02209Y03943*
X02209Y03944*
X02209Y03944*
X02209Y03944*
X02209Y03944*
X0221Y03944*
X0221Y03944*
X0221Y03945*
X0221Y03945*
X0221Y03945*
X0221Y03945*
X0221Y03945*
X0221Y03945*
X0221Y03946*
Y03946*
X0221Y03946*
X0221Y03946*
X0221Y03946*
X0221Y03946*
X0221Y03946*
X0221Y03947*
Y0395*
X02202*
Y03952*
X02221*
Y03944*
G37*
G36*
X02216Y03932D02*
X02216Y03932D01*
X02216Y03932*
X02216Y03932*
X02216Y03932*
X02216Y03932*
X02217Y03931*
X02217Y03931*
X02217Y03931*
X02217Y03931*
X02217Y0393*
X02218Y03929*
X02218Y03929*
X02218Y03929*
X02218Y03929*
X02218Y03929*
X02219Y03929*
X02219Y03929*
X02219Y03928*
X02219Y03928*
X02219Y03928*
X02219Y03928*
X0222Y03928*
X0222Y03927*
X0222Y03927*
X02221Y03927*
X02221Y03927*
Y03925*
X02202*
Y03928*
X02217*
X02217Y03928*
X02217Y03928*
X02217Y03928*
X02217Y03928*
X02216Y03928*
X02216Y03928*
X02216Y03928*
X02216Y03928*
X02216Y03928*
X02216Y03929*
X02216Y03929*
X02216Y03929*
X02215Y03929*
X02215Y03929*
X02215Y0393*
X02215Y0393*
X02215Y0393*
X02215Y0393*
X02215Y0393*
X02215Y0393*
X02215Y0393*
X02215Y03931*
X02215Y03931*
X02214Y03931*
X02214Y03932*
X02214Y03932*
X02214Y03932*
X02216*
X02216Y03932*
G37*
G36*
X02207Y03917D02*
X02207D01*
X02207Y03917*
X02207Y03917*
X02207Y03917*
X02207Y03917*
X02206Y03917*
X02206Y03917*
X02206Y03917*
X02205Y03916*
X02205Y03916*
X02205Y03916*
X02205Y03916*
X02204Y03916*
X02204Y03916*
X02204Y03916*
X02204Y03916*
X02204Y03916*
X02204Y03915*
X02204Y03915*
X02204Y03915*
X02204Y03915*
X02204Y03915*
X02204Y03915*
X02204Y03915*
X02204Y03914*
X02203Y03914*
X02203Y03914*
X02203Y03914*
X02203Y03914*
X02203Y03913*
Y03913*
X02203Y03913*
Y03913*
X02203Y03913*
X02203Y03913*
X02203Y03912*
X02203Y03912*
X02204Y03912*
X02204Y03912*
X02204Y03912*
X02204Y03911*
X02204Y03911*
X02204Y03911*
X02204Y03911*
X02204Y0391*
X02204Y0391*
X02205Y0391*
X02205Y0391*
X02205Y0391*
X02205Y0391*
X02205Y0391*
X02205Y0391*
X02205Y0391*
X02205Y0391*
X02206Y0391*
X02206Y0391*
X02206Y03909*
X02206Y03909*
X02207Y03909*
X02207Y03909*
X02207Y03909*
X02207*
X02207*
X02207*
X02208Y03909*
X02208Y03909*
X02208Y03909*
X02208Y03909*
X02208Y03909*
X02208Y03909*
X02209Y0391*
X02209Y0391*
X02209Y0391*
X02209Y0391*
X0221Y0391*
X0221Y0391*
X0221Y0391*
X0221Y0391*
X0221Y0391*
X0221Y0391*
X0221Y03911*
X0221Y03911*
X0221Y03911*
X0221Y03911*
X0221Y03911*
X02211Y03911*
X02211Y03911*
X02211Y03912*
X02211Y03912*
X02211Y03912*
X02211Y03912*
X02211Y03913*
X02211Y03913*
Y03913*
X02211Y03913*
X02211Y03913*
X02211Y03914*
X02211Y03914*
X02211Y03914*
X02211Y03915*
X02213Y03914*
Y03914*
X02213Y03914*
Y03914*
X02213Y03914*
Y03914*
X02213Y03914*
X02213Y03914*
X02213Y03914*
X02213Y03913*
X02213Y03913*
X02213Y03913*
X02213Y03913*
X02213Y03912*
X02213Y03912*
X02213Y03912*
X02213Y03912*
X02214Y03911*
X02214Y03911*
X02214Y03911*
X02214Y03911*
X02214Y03911*
X02214Y03911*
X02214Y03911*
X02214Y03911*
X02214Y03911*
X02214Y03911*
X02214Y03911*
X02215Y0391*
X02215Y0391*
X02215Y0391*
X02215Y0391*
X02216Y0391*
X02216Y0391*
X02216*
X02216*
X02216*
X02216Y0391*
X02216Y0391*
X02216Y0391*
X02217Y0391*
X02217Y0391*
X02217Y0391*
X02217Y0391*
X02217Y03911*
X02218Y03911*
X02218Y03911*
X02218Y03911*
X02218Y03911*
X02218Y03911*
X02218Y03911*
X02218Y03911*
X02218Y03911*
X02218Y03911*
X02218Y03911*
X02218Y03912*
X02219Y03912*
X02219Y03912*
X02219Y03912*
X02219Y03912*
X02219Y03912*
X02219Y03913*
X02219Y03913*
X02219Y03913*
X02219Y03913*
Y03913*
X02219Y03914*
X02219Y03914*
X02219Y03914*
X02219Y03914*
X02219Y03914*
X02219Y03914*
X02219Y03915*
X02219Y03915*
X02218Y03915*
X02218Y03915*
X02218Y03915*
X02218Y03916*
X02218Y03916*
X02218Y03916*
X02218Y03916*
X02218Y03916*
X02218Y03916*
X02218Y03916*
X02218Y03916*
X02217Y03916*
X02217Y03916*
X02217Y03916*
X02217Y03916*
X02217Y03916*
X02216Y03917*
X02216Y03917*
X02216Y03917*
X02216Y03917*
X02216Y03919*
X02216*
X02216*
X02216Y03919*
X02216Y03919*
X02216Y03919*
X02217Y03919*
X02217Y03919*
X02217Y03919*
X02217Y03919*
X02218Y03919*
X02218Y03918*
X02218Y03918*
X02218Y03918*
X02219Y03918*
X02219Y03918*
X02219Y03917*
X0222Y03917*
X0222Y03917*
X0222Y03917*
X0222Y03917*
X0222Y03917*
X0222Y03917*
X0222Y03917*
X0222Y03916*
X0222Y03916*
X0222Y03916*
X0222Y03916*
X02221Y03915*
X02221Y03915*
X02221Y03915*
X02221Y03914*
X02221Y03914*
X02221Y03913*
Y03913*
X02221Y03913*
Y03913*
X02221Y03913*
X02221Y03913*
X02221Y03912*
X02221Y03912*
X02221Y03912*
X02221Y03911*
X02221Y03911*
X0222Y03911*
X0222Y03911*
X0222Y0391*
X0222Y0391*
X0222Y0391*
X0222Y0391*
X0222Y0391*
X0222Y0391*
X0222Y0391*
X0222Y0391*
X0222Y0391*
X02219Y03909*
X02219Y03909*
X02219Y03909*
X02219Y03909*
X02218Y03908*
X02218Y03908*
X02218Y03908*
X02218Y03908*
X02218Y03908*
X02218Y03908*
X02218Y03908*
X02218Y03908*
X02218Y03908*
X02217Y03908*
X02217Y03908*
X02217Y03908*
X02216Y03908*
X02216Y03908*
X02216Y03908*
X02216*
X02216*
X02216*
X02216Y03908*
X02216*
X02215Y03908*
X02215Y03908*
X02215Y03908*
X02215Y03908*
X02214Y03908*
X02214Y03908*
X02214Y03908*
X02214Y03908*
X02214Y03908*
X02214Y03908*
X02214Y03908*
X02214Y03908*
X02213Y03909*
X02213Y03909*
X02213Y03909*
X02213Y03909*
X02213Y03909*
X02213Y03909*
X02213Y03909*
X02213Y03909*
X02213Y0391*
X02212Y0391*
X02212Y0391*
X02212Y0391*
X02212Y0391*
Y0391*
X02212Y0391*
X02212Y0391*
X02212Y0391*
X02212Y0391*
X02212Y0391*
X02212Y0391*
X02212Y03909*
X02212Y03909*
X02211Y03909*
X02211Y03909*
X02211Y03909*
X02211Y03908*
X02211Y03908*
X02211Y03908*
X0221Y03908*
X0221Y03908*
X0221Y03908*
X0221Y03908*
X0221Y03908*
X0221Y03908*
X0221Y03907*
X0221Y03907*
X0221Y03907*
X02209Y03907*
X02209Y03907*
X02209Y03907*
X02209Y03907*
X02208Y03907*
X02208Y03907*
X02208Y03907*
X02207Y03907*
X02207*
X02207*
X02207Y03907*
X02207Y03907*
X02207Y03907*
X02206Y03907*
X02206Y03907*
X02206Y03907*
X02206Y03907*
X02205Y03907*
X02205Y03907*
X02204Y03908*
X02204Y03908*
X02204Y03908*
X02203Y03908*
X02203Y03909*
X02203Y03909*
X02203Y03909*
X02203Y03909*
X02203Y03909*
X02203Y03909*
X02203Y03909*
X02202Y0391*
X02202Y0391*
X02202Y0391*
X02202Y03911*
X02202Y03911*
X02202Y03911*
X02202Y03912*
X02201Y03912*
X02201Y03913*
X02201Y03913*
Y03913*
X02201Y03914*
X02201Y03914*
X02201Y03914*
X02201Y03914*
X02201Y03914*
X02202Y03915*
X02202Y03915*
X02202Y03915*
X02202Y03916*
X02202Y03916*
X02202Y03916*
X02202Y03917*
X02203Y03917*
X02203Y03917*
X02203Y03917*
X02203Y03918*
X02203Y03918*
X02203Y03918*
X02203Y03918*
X02203Y03918*
X02204Y03918*
X02204Y03918*
X02204Y03918*
X02204Y03919*
X02205Y03919*
X02205Y03919*
X02206Y03919*
X02206Y03919*
X02206Y03919*
X02207Y03919*
X02207Y03917*
G37*
%LNgrandmaster-2*%
%LPC*%
G36*
X01297Y04155D02*
X01297D01*
X01297*
X01297*
X01297*
X01297*
X01296*
X01296*
X01296Y04155*
X01296*
X01296Y04155*
X01296*
X01295Y04155*
X01295Y04155*
X01294Y04155*
X01294Y04155*
X01293Y04154*
X01293Y04154*
X01292Y04154*
X01292Y04154*
X01291Y04154*
X01291Y04154*
X01291Y04154*
X01291Y04154*
X01291Y04154*
X0129Y04154*
X0129Y04154*
X0129Y04153*
X0129Y04153*
X0129Y04153*
X0129Y04153*
X0129Y04153*
X0129Y04153*
X0129Y04153*
X01289Y04152*
X01289Y04152*
X01289Y04152*
X01289Y04152*
X01289Y04151*
X01289Y04151*
X01289Y04151*
Y04151*
X01289Y04151*
X01289Y04151*
X01289Y0415*
X01289Y0415*
X01289Y0415*
X01289Y0415*
X01289Y0415*
X01289Y0415*
X01289Y04149*
X0129Y04149*
X0129Y04149*
X0129Y04149*
X0129Y04148*
X0129Y04148*
X0129Y04148*
X0129Y04148*
X01291Y04148*
X01291Y04148*
X01291Y04148*
X01291Y04148*
X01291Y04148*
X01292Y04148*
X01292Y04148*
X01292Y04148*
X01292Y04148*
X01293Y04147*
X01293Y04147*
X01293Y04147*
X01293Y04147*
X01294Y04147*
X01294Y04147*
X01294Y04147*
X01295Y04147*
X01295Y04147*
X01296Y04147*
X01296Y04147*
X01296Y04147*
X01297*
X01297*
X01297*
X01297*
X01297*
X01297*
X01297Y04147*
X01297*
X01298*
X01298Y04147*
X01298*
X01298Y04147*
X01299Y04147*
X01299Y04147*
X013Y04147*
X013Y04147*
X01301Y04147*
X01301Y04148*
X01302Y04148*
X01302Y04148*
X01303Y04148*
X01303Y04148*
X01303Y04148*
X01303Y04148*
X01303Y04148*
X01303Y04148*
X01303Y04148*
X01303Y04148*
X01303Y04148*
X01303Y04149*
X01304Y04149*
X01304Y04149*
X01304Y04149*
X01304Y04149*
X01304Y0415*
X01304Y0415*
X01304Y0415*
X01304Y0415*
X01305Y04151*
X01305Y04151*
Y04151*
X01305Y04151*
X01305Y04151*
X01305Y04151*
X01304Y04151*
X01304Y04152*
X01304Y04152*
X01304Y04152*
X01304Y04152*
X01304Y04152*
X01304Y04153*
X01304Y04153*
X01304Y04153*
X01303Y04153*
X01303Y04154*
X01303Y04154*
X01303Y04154*
X01303Y04154*
X01303Y04154*
X01303Y04154*
X01302Y04154*
X01302Y04154*
X01302Y04154*
X01301Y04154*
X01301Y04154*
X01301Y04154*
X01301Y04154*
X01301Y04154*
X013Y04154*
X013Y04155*
X013Y04155*
X01299Y04155*
X01299Y04155*
X01299Y04155*
X01298Y04155*
X01298Y04155*
X01298Y04155*
X01297Y04155*
G37*
G36*
X01292Y04124D02*
X01292D01*
X01292*
X01292*
X01292Y04124*
X01292Y04124*
X01292Y04124*
X01292Y04124*
X01292Y04124*
X01291Y04124*
X01291Y04124*
X01291Y04124*
X01291Y04124*
X01291Y04124*
X0129Y04124*
X0129Y04123*
X0129Y04123*
X0129Y04123*
X0129Y04123*
X0129Y04123*
X0129Y04123*
X0129Y04123*
X0129Y04123*
X0129Y04123*
X0129Y04122*
X0129Y04122*
X01289Y04122*
X01289Y04122*
X01289Y04122*
X01289Y04121*
X01289Y04121*
X01289Y04121*
X01289Y0412*
Y04114*
X01295*
Y0412*
X01295Y0412*
Y0412*
X01295Y0412*
X01295Y04121*
X01295Y04121*
X01295Y04121*
X01295Y04122*
X01295Y04122*
X01295Y04122*
Y04122*
X01295Y04122*
X01295Y04122*
X01295Y04122*
X01295Y04122*
X01295Y04123*
X01295Y04123*
X01295Y04123*
X01295Y04123*
X01294Y04124*
X01294Y04124*
X01294*
X01294Y04124*
X01294Y04124*
X01294Y04124*
X01294Y04124*
X01294Y04124*
X01293Y04124*
X01293Y04124*
X01293Y04124*
X01293Y04124*
X01292Y04124*
G37*
G36*
X01295Y04014D02*
X01295D01*
X01295*
X01295*
X01295Y04014*
X01295Y04014*
X01295Y04014*
X01295Y04014*
X01295Y04014*
X01294Y04014*
X01294Y04014*
X01294Y04014*
X01294Y04013*
X01294Y04013*
X01294Y04013*
X01293Y04013*
X01293Y04013*
X01293Y04013*
X01293Y04013*
X01293Y04013*
X01293Y04013*
X01293Y04013*
X01293Y04012*
X01293Y04012*
X01293Y04012*
X01293Y04012*
X01293Y04012*
X01293Y04011*
X01292Y04011*
X01292Y04011*
X01292Y0401*
X01292Y0401*
X01292Y0401*
Y04004*
X01299*
Y04009*
X01299Y0401*
Y0401*
X01299Y0401*
X01299Y0401*
X01299Y04011*
X01298Y04011*
X01298Y04011*
X01298Y04012*
X01298Y04012*
Y04012*
X01298Y04012*
X01298Y04012*
X01298Y04012*
X01298Y04012*
X01298Y04012*
X01298Y04012*
X01298Y04013*
X01298Y04013*
X01297Y04013*
X01297Y04013*
X01297*
X01297Y04013*
X01297Y04013*
X01297Y04013*
X01297Y04013*
X01297Y04013*
X01297Y04014*
X01296Y04014*
X01296Y04014*
X01296Y04014*
X01295Y04014*
G37*
G36*
X02157Y03949D02*
X0215D01*
Y03943*
X0215Y03943*
Y03943*
X0215Y03943*
X0215Y03942*
X0215Y03942*
X0215Y03942*
X0215Y03941*
X0215Y03941*
X02151Y03941*
Y03941*
X02151Y03941*
X02151Y03941*
X02151Y03941*
X02151Y0394*
X02151Y0394*
X02151Y0394*
X02151Y0394*
X02151Y0394*
X02151Y03939*
X02152Y03939*
X02152*
X02152Y03939*
X02152Y03939*
X02152Y03939*
X02152Y03939*
X02152Y03939*
X02152Y03939*
X02152Y03939*
X02153Y03939*
X02153Y03939*
X02153Y03939*
X02153*
X02153*
X02154*
X02154Y03939*
X02154Y03939*
X02154Y03939*
X02154Y03939*
X02154Y03939*
X02154Y03939*
X02155Y03939*
X02155Y03939*
X02155Y03939*
X02155Y03939*
X02155Y03939*
X02155Y0394*
X02156Y0394*
X02156Y0394*
X02156Y0394*
X02156Y0394*
X02156Y0394*
X02156Y0394*
X02156Y0394*
X02156Y0394*
X02156Y0394*
X02156Y03941*
X02156Y03941*
X02156Y03941*
X02156Y03941*
X02156Y03942*
X02156Y03942*
X02157Y03942*
X02157Y03943*
Y03949*
G37*
G36*
X02219Y0395D02*
X02212D01*
Y03944*
X02212Y03944*
Y03944*
X02212Y03944*
X02212Y03943*
X02212Y03943*
X02213Y03943*
X02213Y03942*
X02213Y03942*
X02213Y03942*
Y03942*
X02213Y03942*
X02213Y03942*
X02213Y03942*
X02213Y03942*
X02213Y03941*
X02213Y03941*
X02213Y03941*
X02213Y03941*
X02214Y0394*
X02214Y0394*
X02214*
X02214Y0394*
X02214Y0394*
X02214Y0394*
X02214Y0394*
X02214Y0394*
X02214Y0394*
X02215Y0394*
X02215Y0394*
X02215Y0394*
X02216Y0394*
X02216*
X02216*
X02216*
X02216Y0394*
X02216Y0394*
X02216Y0394*
X02216Y0394*
X02216Y0394*
X02217Y0394*
X02217Y0394*
X02217Y0394*
X02217Y0394*
X02217Y0394*
X02217Y0394*
X02218Y03941*
X02218Y03941*
X02218Y03941*
X02218Y03941*
X02218Y03941*
X02218Y03941*
X02218Y03941*
X02218Y03941*
X02218Y03941*
X02218Y03942*
X02218Y03942*
X02218Y03942*
X02218Y03942*
X02219Y03942*
X02219Y03943*
X02219Y03943*
X02219Y03943*
X02219Y03944*
Y0395*
G37*
%LNgrandmaster-3*%
%LPD*%
G54D10*
X02761Y0332D02*
D01*
X02761Y03321*
X02761Y03321*
X02761Y03321*
X02761Y03322*
X02761Y03322*
X02761Y03322*
X02761Y03322*
X02761Y03323*
X0276Y03323*
X0276Y03323*
X0276Y03324*
X0276Y03324*
X02759Y03324*
X02759Y03324*
X02759Y03324*
X02759Y03325*
X02758Y03325*
X02758Y03325*
X02758Y03325*
X02757Y03325*
X02757Y03325*
X02757Y03325*
X02756*
X02756Y03325*
X02756Y03325*
X02755Y03325*
X02755Y03325*
X02755Y03325*
X02754Y03325*
X02754Y03324*
X02754Y03324*
X02753Y03324*
X02753Y03324*
X02753Y03324*
X02753Y03323*
X02752Y03323*
X02752Y03323*
X02752Y03322*
X02752Y03322*
X02752Y03322*
X02752Y03322*
X02752Y03321*
X02752Y03321*
X02751Y03321*
X02751Y0332*
X02751Y0332*
X02752Y03319*
X02752Y03319*
X02752Y03319*
X02752Y03318*
X02752Y03318*
X02752Y03318*
X02752Y03318*
X02752Y03317*
X02753Y03317*
X02753Y03317*
X02753Y03317*
X02753Y03316*
X02754Y03316*
X02754Y03316*
X02754Y03316*
X02755Y03316*
X02755Y03315*
X02755Y03315*
X02756Y03315*
X02756Y03315*
X02756Y03315*
X02757*
X02757Y03315*
X02757Y03315*
X02758Y03315*
X02758Y03315*
X02758Y03316*
X02759Y03316*
X02759Y03316*
X02759Y03316*
X02759Y03316*
X0276Y03317*
X0276Y03317*
X0276Y03317*
X0276Y03317*
X02761Y03318*
X02761Y03318*
X02761Y03318*
X02761Y03318*
X02761Y03319*
X02761Y03319*
X02761Y03319*
X02761Y0332*
X02761Y0332*
X03531Y0375D02*
D01*
X03531Y0375*
X03531Y03751*
X03531Y03751*
X03531Y03751*
X03531Y03752*
X03531Y03752*
X03531Y03752*
X03531Y03752*
X0353Y03753*
X0353Y03753*
X0353Y03753*
X0353Y03754*
X03529Y03754*
X03529Y03754*
X03529Y03754*
X03529Y03754*
X03528Y03754*
X03528Y03755*
X03528Y03755*
X03527Y03755*
X03527Y03755*
X03527Y03755*
X03526*
X03526Y03755*
X03526Y03755*
X03525Y03755*
X03525Y03755*
X03525Y03754*
X03524Y03754*
X03524Y03754*
X03524Y03754*
X03523Y03754*
X03523Y03754*
X03523Y03753*
X03523Y03753*
X03522Y03753*
X03522Y03752*
X03522Y03752*
X03522Y03752*
X03522Y03752*
X03522Y03751*
X03522Y03751*
X03522Y03751*
X03522Y0375*
X03522Y0375*
X03522Y0375*
X03522Y03749*
X03522Y03749*
X03522Y03748*
X03522Y03748*
X03522Y03748*
X03522Y03748*
X03522Y03747*
X03522Y03747*
X03523Y03747*
X03523Y03746*
X03523Y03746*
X03523Y03746*
X03524Y03746*
X03524Y03746*
X03524Y03745*
X03525Y03745*
X03525Y03745*
X03525Y03745*
X03526Y03745*
X03526Y03745*
X03526Y03745*
X03527*
X03527Y03745*
X03527Y03745*
X03528Y03745*
X03528Y03745*
X03528Y03745*
X03529Y03745*
X03529Y03746*
X03529Y03746*
X03529Y03746*
X0353Y03746*
X0353Y03746*
X0353Y03747*
X0353Y03747*
X03531Y03747*
X03531Y03748*
X03531Y03748*
X03531Y03748*
X03531Y03748*
X03531Y03749*
X03531Y03749*
X03531Y0375*
X03531Y0375*
X01636Y0423D02*
D01*
X01636Y0423*
X01636Y0423*
X01636Y04231*
X01636Y04231*
X01636Y04231*
X01636Y04232*
X01635Y04232*
X01635Y04232*
X01635Y04232*
X01635Y04233*
X01635Y04233*
X01634Y04233*
X01634Y04233*
X01634Y04234*
X01634Y04234*
X01633Y04234*
X01633Y04234*
X01633Y04234*
X01632Y04234*
X01632Y04234*
X01632Y04234*
X01631Y04234*
X01631*
X01631Y04234*
X0163Y04234*
X0163Y04234*
X0163Y04234*
X01629Y04234*
X01629Y04234*
X01629Y04234*
X01628Y04234*
X01628Y04233*
X01628Y04233*
X01628Y04233*
X01627Y04233*
X01627Y04232*
X01627Y04232*
X01627Y04232*
X01627Y04232*
X01626Y04231*
X01626Y04231*
X01626Y04231*
X01626Y0423*
X01626Y0423*
X01626Y0423*
X01626Y04229*
X01626Y04229*
X01626Y04229*
X01626Y04228*
X01626Y04228*
X01627Y04228*
X01627Y04227*
X01627Y04227*
X01627Y04227*
X01627Y04226*
X01628Y04226*
X01628Y04226*
X01628Y04226*
X01628Y04225*
X01629Y04225*
X01629Y04225*
X01629Y04225*
X0163Y04225*
X0163Y04225*
X0163Y04225*
X01631Y04225*
X01631Y04225*
X01631*
X01632Y04225*
X01632Y04225*
X01632Y04225*
X01633Y04225*
X01633Y04225*
X01633Y04225*
X01634Y04225*
X01634Y04225*
X01634Y04226*
X01634Y04226*
X01635Y04226*
X01635Y04226*
X01635Y04227*
X01635Y04227*
X01635Y04227*
X01636Y04228*
X01636Y04228*
X01636Y04228*
X01636Y04229*
X01636Y04229*
X01636Y04229*
X01636Y0423*
X04332Y00833D02*
D01*
X04332Y00834*
X04332Y00834*
X04332Y00834*
X04332Y00835*
X04332Y00835*
X04332Y00835*
X04332Y00836*
X04331Y00836*
X04331Y00836*
X04331Y00837*
X04331Y00837*
X04331Y00837*
X0433Y00837*
X0433Y00837*
X0433Y00838*
X04329Y00838*
X04329Y00838*
X04329Y00838*
X04328Y00838*
X04328Y00838*
X04328Y00838*
X04327Y00838*
X04327*
X04327Y00838*
X04326Y00838*
X04326Y00838*
X04326Y00838*
X04325Y00838*
X04325Y00838*
X04325Y00838*
X04325Y00837*
X04324Y00837*
X04324Y00837*
X04324Y00837*
X04323Y00837*
X04323Y00836*
X04323Y00836*
X04323Y00836*
X04323Y00835*
X04323Y00835*
X04323Y00835*
X04322Y00834*
X04322Y00834*
X04322Y00834*
X04322Y00833*
X04322Y00833*
X04322Y00833*
X04322Y00832*
X04323Y00832*
X04323Y00832*
X04323Y00831*
X04323Y00831*
X04323Y00831*
X04323Y0083*
X04323Y0083*
X04324Y0083*
X04324Y0083*
X04324Y00829*
X04325Y00829*
X04325Y00829*
X04325Y00829*
X04325Y00829*
X04326Y00829*
X04326Y00829*
X04326Y00829*
X04327Y00828*
X04327Y00828*
X04327*
X04328Y00828*
X04328Y00829*
X04328Y00829*
X04329Y00829*
X04329Y00829*
X04329Y00829*
X0433Y00829*
X0433Y00829*
X0433Y00829*
X04331Y0083*
X04331Y0083*
X04331Y0083*
X04331Y0083*
X04331Y00831*
X04332Y00831*
X04332Y00831*
X04332Y00832*
X04332Y00832*
X04332Y00832*
X04332Y00833*
X04332Y00833*
X04332Y00833*
X01217Y00822D02*
D01*
X01217Y00822*
X01217Y00823*
X01216Y00823*
X01216Y00823*
X01216Y00824*
X01216Y00824*
X01216Y00824*
X01216Y00825*
X01216Y00825*
X01215Y00825*
X01215Y00825*
X01215Y00826*
X01215Y00826*
X01214Y00826*
X01214Y00826*
X01214Y00826*
X01214Y00826*
X01213Y00827*
X01213Y00827*
X01213Y00827*
X01212Y00827*
X01212Y00827*
X01211*
X01211Y00827*
X01211Y00827*
X0121Y00827*
X0121Y00827*
X0121Y00826*
X0121Y00826*
X01209Y00826*
X01209Y00826*
X01209Y00826*
X01208Y00826*
X01208Y00825*
X01208Y00825*
X01208Y00825*
X01207Y00825*
X01207Y00824*
X01207Y00824*
X01207Y00824*
X01207Y00823*
X01207Y00823*
X01207Y00823*
X01207Y00822*
X01207Y00822*
X01207Y00822*
X01207Y00821*
X01207Y00821*
X01207Y00821*
X01207Y0082*
X01207Y0082*
X01207Y0082*
X01207Y00819*
X01208Y00819*
X01208Y00819*
X01208Y00818*
X01208Y00818*
X01209Y00818*
X01209Y00818*
X01209Y00818*
X0121Y00817*
X0121Y00817*
X0121Y00817*
X0121Y00817*
X01211Y00817*
X01211Y00817*
X01211Y00817*
X01212*
X01212Y00817*
X01213Y00817*
X01213Y00817*
X01213Y00817*
X01214Y00817*
X01214Y00817*
X01214Y00818*
X01214Y00818*
X01215Y00818*
X01215Y00818*
X01215Y00818*
X01215Y00819*
X01216Y00819*
X01216Y00819*
X01216Y0082*
X01216Y0082*
X01216Y0082*
X01216Y00821*
X01216Y00821*
X01217Y00821*
X01217Y00822*
X01217Y00822*
X02896Y0375D02*
D01*
X02896Y0375*
X02896Y03751*
X02896Y03751*
X02896Y03751*
X02896Y03752*
X02896Y03752*
X02896Y03752*
X02896Y03752*
X02895Y03753*
X02895Y03753*
X02895Y03753*
X02895Y03754*
X02894Y03754*
X02894Y03754*
X02894Y03754*
X02894Y03754*
X02893Y03754*
X02893Y03755*
X02893Y03755*
X02892Y03755*
X02892Y03755*
X02892Y03755*
X02891*
X02891Y03755*
X02891Y03755*
X0289Y03755*
X0289Y03755*
X0289Y03754*
X02889Y03754*
X02889Y03754*
X02889Y03754*
X02888Y03754*
X02888Y03754*
X02888Y03753*
X02888Y03753*
X02887Y03753*
X02887Y03752*
X02887Y03752*
X02887Y03752*
X02887Y03752*
X02887Y03751*
X02887Y03751*
X02887Y03751*
X02887Y0375*
X02887Y0375*
X02887Y0375*
X02887Y03749*
X02887Y03749*
X02887Y03748*
X02887Y03748*
X02887Y03748*
X02887Y03748*
X02887Y03747*
X02887Y03747*
X02888Y03747*
X02888Y03746*
X02888Y03746*
X02888Y03746*
X02889Y03746*
X02889Y03746*
X02889Y03745*
X0289Y03745*
X0289Y03745*
X0289Y03745*
X02891Y03745*
X02891Y03745*
X02891Y03745*
X02892*
X02892Y03745*
X02892Y03745*
X02893Y03745*
X02893Y03745*
X02893Y03745*
X02894Y03745*
X02894Y03746*
X02894Y03746*
X02894Y03746*
X02895Y03746*
X02895Y03746*
X02895Y03747*
X02895Y03747*
X02896Y03747*
X02896Y03748*
X02896Y03748*
X02896Y03748*
X02896Y03748*
X02896Y03749*
X02896Y03749*
X02896Y0375*
X02896Y0375*
X02781D02*
D01*
X02781Y0375*
X02781Y03751*
X02781Y03751*
X02781Y03751*
X02781Y03752*
X02781Y03752*
X02781Y03752*
X02781Y03752*
X0278Y03753*
X0278Y03753*
X0278Y03753*
X0278Y03754*
X02779Y03754*
X02779Y03754*
X02779Y03754*
X02779Y03754*
X02778Y03754*
X02778Y03755*
X02778Y03755*
X02777Y03755*
X02777Y03755*
X02777Y03755*
X02776*
X02776Y03755*
X02776Y03755*
X02775Y03755*
X02775Y03755*
X02775Y03754*
X02774Y03754*
X02774Y03754*
X02774Y03754*
X02773Y03754*
X02773Y03754*
X02773Y03753*
X02773Y03753*
X02772Y03753*
X02772Y03752*
X02772Y03752*
X02772Y03752*
X02772Y03752*
X02772Y03751*
X02772Y03751*
X02772Y03751*
X02772Y0375*
X02772Y0375*
X02772Y0375*
X02772Y03749*
X02772Y03749*
X02772Y03748*
X02772Y03748*
X02772Y03748*
X02772Y03748*
X02772Y03747*
X02772Y03747*
X02773Y03747*
X02773Y03746*
X02773Y03746*
X02773Y03746*
X02774Y03746*
X02774Y03746*
X02774Y03745*
X02775Y03745*
X02775Y03745*
X02775Y03745*
X02776Y03745*
X02776Y03745*
X02776Y03745*
X02777*
X02777Y03745*
X02777Y03745*
X02778Y03745*
X02778Y03745*
X02778Y03745*
X02779Y03745*
X02779Y03746*
X02779Y03746*
X02779Y03746*
X0278Y03746*
X0278Y03746*
X0278Y03747*
X0278Y03747*
X02781Y03747*
X02781Y03748*
X02781Y03748*
X02781Y03748*
X02781Y03748*
X02781Y03749*
X02781Y03749*
X02781Y0375*
X02781Y0375*
X03306D02*
D01*
X03306Y0375*
X03306Y03751*
X03306Y03751*
X03306Y03751*
X03306Y03752*
X03306Y03752*
X03306Y03752*
X03306Y03752*
X03305Y03753*
X03305Y03753*
X03305Y03753*
X03305Y03754*
X03304Y03754*
X03304Y03754*
X03304Y03754*
X03304Y03754*
X03303Y03754*
X03303Y03755*
X03303Y03755*
X03302Y03755*
X03302Y03755*
X03302Y03755*
X03301*
X03301Y03755*
X03301Y03755*
X033Y03755*
X033Y03755*
X033Y03754*
X03299Y03754*
X03299Y03754*
X03299Y03754*
X03298Y03754*
X03298Y03754*
X03298Y03753*
X03298Y03753*
X03297Y03753*
X03297Y03752*
X03297Y03752*
X03297Y03752*
X03297Y03752*
X03297Y03751*
X03297Y03751*
X03297Y03751*
X03297Y0375*
X03297Y0375*
X03297Y0375*
X03297Y03749*
X03297Y03749*
X03297Y03748*
X03297Y03748*
X03297Y03748*
X03297Y03748*
X03297Y03747*
X03297Y03747*
X03298Y03747*
X03298Y03746*
X03298Y03746*
X03298Y03746*
X03299Y03746*
X03299Y03746*
X03299Y03745*
X033Y03745*
X033Y03745*
X033Y03745*
X03301Y03745*
X03301Y03745*
X03301Y03745*
X03302*
X03302Y03745*
X03302Y03745*
X03303Y03745*
X03303Y03745*
X03303Y03745*
X03304Y03745*
X03304Y03746*
X03304Y03746*
X03304Y03746*
X03305Y03746*
X03305Y03746*
X03305Y03747*
X03305Y03747*
X03306Y03747*
X03306Y03748*
X03306Y03748*
X03306Y03748*
X03306Y03748*
X03306Y03749*
X03306Y03749*
X03306Y0375*
X03306Y0375*
X01217Y01872D02*
D01*
X01217Y01872*
X01217Y01873*
X01216Y01873*
X01216Y01873*
X01216Y01874*
X01216Y01874*
X01216Y01874*
X01216Y01875*
X01216Y01875*
X01215Y01875*
X01215Y01875*
X01215Y01876*
X01215Y01876*
X01214Y01876*
X01214Y01876*
X01214Y01876*
X01214Y01876*
X01213Y01877*
X01213Y01877*
X01213Y01877*
X01212Y01877*
X01212Y01877*
X01211*
X01211Y01877*
X01211Y01877*
X0121Y01877*
X0121Y01877*
X0121Y01876*
X0121Y01876*
X01209Y01876*
X01209Y01876*
X01209Y01876*
X01208Y01876*
X01208Y01875*
X01208Y01875*
X01208Y01875*
X01207Y01875*
X01207Y01874*
X01207Y01874*
X01207Y01874*
X01207Y01873*
X01207Y01873*
X01207Y01873*
X01207Y01872*
X01207Y01872*
X01207Y01872*
X01207Y01871*
X01207Y01871*
X01207Y01871*
X01207Y0187*
X01207Y0187*
X01207Y0187*
X01207Y01869*
X01208Y01869*
X01208Y01869*
X01208Y01868*
X01208Y01868*
X01209Y01868*
X01209Y01868*
X01209Y01868*
X0121Y01867*
X0121Y01867*
X0121Y01867*
X0121Y01867*
X01211Y01867*
X01211Y01867*
X01211Y01867*
X01212*
X01212Y01867*
X01213Y01867*
X01213Y01867*
X01213Y01867*
X01214Y01867*
X01214Y01867*
X01214Y01868*
X01214Y01868*
X01215Y01868*
X01215Y01868*
X01215Y01868*
X01215Y01869*
X01216Y01869*
X01216Y01869*
X01216Y0187*
X01216Y0187*
X01216Y0187*
X01216Y01871*
X01216Y01871*
X01217Y01871*
X01217Y01872*
X01217Y01872*
Y02397D02*
D01*
X01217Y02397*
X01217Y02398*
X01216Y02398*
X01216Y02398*
X01216Y02399*
X01216Y02399*
X01216Y02399*
X01216Y024*
X01216Y024*
X01215Y024*
X01215Y024*
X01215Y02401*
X01215Y02401*
X01214Y02401*
X01214Y02401*
X01214Y02401*
X01214Y02401*
X01213Y02402*
X01213Y02402*
X01213Y02402*
X01212Y02402*
X01212Y02402*
X01211*
X01211Y02402*
X01211Y02402*
X0121Y02402*
X0121Y02402*
X0121Y02401*
X0121Y02401*
X01209Y02401*
X01209Y02401*
X01209Y02401*
X01208Y02401*
X01208Y024*
X01208Y024*
X01208Y024*
X01207Y024*
X01207Y02399*
X01207Y02399*
X01207Y02399*
X01207Y02398*
X01207Y02398*
X01207Y02398*
X01207Y02397*
X01207Y02397*
X01207Y02397*
X01207Y02396*
X01207Y02396*
X01207Y02396*
X01207Y02395*
X01207Y02395*
X01207Y02395*
X01207Y02394*
X01208Y02394*
X01208Y02394*
X01208Y02393*
X01208Y02393*
X01209Y02393*
X01209Y02393*
X01209Y02393*
X0121Y02392*
X0121Y02392*
X0121Y02392*
X0121Y02392*
X01211Y02392*
X01211Y02392*
X01211Y02392*
X01212*
X01212Y02392*
X01213Y02392*
X01213Y02392*
X01213Y02392*
X01214Y02392*
X01214Y02392*
X01214Y02393*
X01214Y02393*
X01215Y02393*
X01215Y02393*
X01215Y02393*
X01215Y02394*
X01216Y02394*
X01216Y02394*
X01216Y02395*
X01216Y02395*
X01216Y02395*
X01216Y02396*
X01216Y02396*
X01217Y02396*
X01217Y02397*
X01217Y02397*
Y01347D02*
D01*
X01217Y01347*
X01217Y01348*
X01216Y01348*
X01216Y01348*
X01216Y01349*
X01216Y01349*
X01216Y01349*
X01216Y0135*
X01216Y0135*
X01215Y0135*
X01215Y0135*
X01215Y01351*
X01215Y01351*
X01214Y01351*
X01214Y01351*
X01214Y01351*
X01214Y01351*
X01213Y01352*
X01213Y01352*
X01213Y01352*
X01212Y01352*
X01212Y01352*
X01211*
X01211Y01352*
X01211Y01352*
X0121Y01352*
X0121Y01352*
X0121Y01351*
X0121Y01351*
X01209Y01351*
X01209Y01351*
X01209Y01351*
X01208Y01351*
X01208Y0135*
X01208Y0135*
X01208Y0135*
X01207Y0135*
X01207Y01349*
X01207Y01349*
X01207Y01349*
X01207Y01348*
X01207Y01348*
X01207Y01348*
X01207Y01347*
X01207Y01347*
X01207Y01347*
X01207Y01346*
X01207Y01346*
X01207Y01346*
X01207Y01345*
X01207Y01345*
X01207Y01345*
X01207Y01344*
X01208Y01344*
X01208Y01344*
X01208Y01343*
X01208Y01343*
X01209Y01343*
X01209Y01343*
X01209Y01343*
X0121Y01342*
X0121Y01342*
X0121Y01342*
X0121Y01342*
X01211Y01342*
X01211Y01342*
X01211Y01342*
X01212*
X01212Y01342*
X01213Y01342*
X01213Y01342*
X01213Y01342*
X01214Y01342*
X01214Y01342*
X01214Y01343*
X01214Y01343*
X01215Y01343*
X01215Y01343*
X01215Y01343*
X01215Y01344*
X01216Y01344*
X01216Y01344*
X01216Y01345*
X01216Y01345*
X01216Y01345*
X01216Y01346*
X01216Y01346*
X01217Y01346*
X01217Y01347*
X01217Y01347*
X03777Y03889D02*
D01*
X03777Y03889*
X03777Y03889*
X03777Y0389*
X03777Y0389*
X03777Y0389*
X03777Y03891*
X03776Y03891*
X03776Y03891*
X03776Y03891*
X03776Y03892*
X03776Y03892*
X03775Y03892*
X03775Y03892*
X03775Y03893*
X03775Y03893*
X03774Y03893*
X03774Y03893*
X03774Y03893*
X03773Y03893*
X03773Y03893*
X03773Y03893*
X03772Y03893*
X03772*
X03772Y03893*
X03771Y03893*
X03771Y03893*
X03771Y03893*
X0377Y03893*
X0377Y03893*
X0377Y03893*
X03769Y03893*
X03769Y03892*
X03769Y03892*
X03769Y03892*
X03768Y03892*
X03768Y03891*
X03768Y03891*
X03768Y03891*
X03768Y03891*
X03767Y0389*
X03767Y0389*
X03767Y0389*
X03767Y03889*
X03767Y03889*
X03767Y03889*
X03767Y03888*
X03767Y03888*
X03767Y03888*
X03767Y03887*
X03767Y03887*
X03768Y03887*
X03768Y03886*
X03768Y03886*
X03768Y03886*
X03768Y03885*
X03769Y03885*
X03769Y03885*
X03769Y03885*
X03769Y03885*
X0377Y03884*
X0377Y03884*
X0377Y03884*
X03771Y03884*
X03771Y03884*
X03771Y03884*
X03772Y03884*
X03772Y03884*
X03772*
X03773Y03884*
X03773Y03884*
X03773Y03884*
X03774Y03884*
X03774Y03884*
X03774Y03884*
X03775Y03884*
X03775Y03885*
X03775Y03885*
X03775Y03885*
X03776Y03885*
X03776Y03885*
X03776Y03886*
X03776Y03886*
X03776Y03886*
X03777Y03887*
X03777Y03887*
X03777Y03887*
X03777Y03888*
X03777Y03888*
X03777Y03888*
X03777Y03889*
G54D11*
X02863Y03279D02*
D01*
X02863Y0328*
X02863Y03281*
X02862Y03281*
X02862Y03282*
X02862Y03283*
X02862Y03284*
X02861Y03285*
X02861Y03285*
X0286Y03286*
X0286Y03287*
X02859Y03287*
X02859Y03288*
X02858Y03288*
X02857Y03289*
X02857Y03289*
X02856Y0329*
X02855Y0329*
X02855Y0329*
X02854Y0329*
X02853Y03291*
X02852Y03291*
X02851Y03291*
X0285*
X0285Y03291*
X02849Y03291*
X02848Y0329*
X02847Y0329*
X02846Y0329*
X02846Y0329*
X02845Y03289*
X02844Y03289*
X02844Y03288*
X02843Y03288*
X02842Y03287*
X02842Y03287*
X02841Y03286*
X02841Y03285*
X0284Y03285*
X0284Y03284*
X0284Y03283*
X0284Y03282*
X02839Y03281*
X02839Y03281*
X02839Y0328*
X02839Y03279*
X02839Y03278*
X02839Y03277*
X02839Y03277*
X0284Y03276*
X0284Y03275*
X0284Y03274*
X0284Y03273*
X02841Y03273*
X02841Y03272*
X02842Y03271*
X02842Y03271*
X02843Y0327*
X02844Y0327*
X02844Y03269*
X02845Y03269*
X02846Y03268*
X02846Y03268*
X02847Y03268*
X02848Y03268*
X02849Y03267*
X0285Y03267*
X0285Y03267*
X02851*
X02852Y03267*
X02853Y03267*
X02854Y03268*
X02855Y03268*
X02855Y03268*
X02856Y03268*
X02857Y03269*
X02857Y03269*
X02858Y0327*
X02859Y0327*
X02859Y03271*
X0286Y03271*
X0286Y03272*
X02861Y03273*
X02861Y03273*
X02862Y03274*
X02862Y03275*
X02862Y03276*
X02862Y03277*
X02863Y03277*
X02863Y03278*
X02863Y03279*
X01727Y04171D02*
D01*
X01727Y04171*
X01726Y04172*
X01726Y04173*
X01726Y04174*
X01726Y04175*
X01726Y04175*
X01725Y04176*
X01725Y04177*
X01724Y04178*
X01724Y04178*
X01723Y04179*
X01723Y04179*
X01722Y0418*
X01721Y0418*
X01721Y04181*
X0172Y04181*
X01719Y04182*
X01718Y04182*
X01718Y04182*
X01717Y04182*
X01716Y04182*
X01715Y04182*
X01714*
X01713Y04182*
X01713Y04182*
X01712Y04182*
X01711Y04182*
X0171Y04182*
X0171Y04181*
X01709Y04181*
X01708Y0418*
X01707Y0418*
X01707Y04179*
X01706Y04179*
X01706Y04178*
X01705Y04178*
X01705Y04177*
X01704Y04176*
X01704Y04175*
X01704Y04175*
X01703Y04174*
X01703Y04173*
X01703Y04172*
X01703Y04171*
X01703Y04171*
X01703Y0417*
X01703Y04169*
X01703Y04168*
X01703Y04167*
X01704Y04167*
X01704Y04166*
X01704Y04165*
X01705Y04164*
X01705Y04164*
X01706Y04163*
X01706Y04162*
X01707Y04162*
X01707Y04161*
X01708Y04161*
X01709Y0416*
X0171Y0416*
X0171Y0416*
X01711Y04159*
X01712Y04159*
X01713Y04159*
X01713Y04159*
X01714Y04159*
X01715*
X01716Y04159*
X01717Y04159*
X01718Y04159*
X01718Y04159*
X01719Y0416*
X0172Y0416*
X01721Y0416*
X01721Y04161*
X01722Y04161*
X01723Y04162*
X01723Y04162*
X01724Y04163*
X01724Y04164*
X01725Y04164*
X01725Y04165*
X01726Y04166*
X01726Y04167*
X01726Y04167*
X01726Y04168*
X01726Y04169*
X01727Y0417*
X01727Y04171*
X03868Y0383D02*
D01*
X03868Y0383*
X03867Y03831*
X03867Y03832*
X03867Y03833*
X03867Y03834*
X03867Y03834*
X03866Y03835*
X03866Y03836*
X03865Y03837*
X03865Y03837*
X03864Y03838*
X03864Y03838*
X03863Y03839*
X03862Y03839*
X03862Y0384*
X03861Y0384*
X0386Y03841*
X03859Y03841*
X03859Y03841*
X03858Y03841*
X03857Y03841*
X03856Y03841*
X03855*
X03854Y03841*
X03854Y03841*
X03853Y03841*
X03852Y03841*
X03851Y03841*
X03851Y0384*
X0385Y0384*
X03849Y03839*
X03848Y03839*
X03848Y03838*
X03847Y03838*
X03847Y03837*
X03846Y03837*
X03846Y03836*
X03845Y03835*
X03845Y03834*
X03845Y03834*
X03844Y03833*
X03844Y03832*
X03844Y03831*
X03844Y0383*
X03844Y0383*
X03844Y03829*
X03844Y03828*
X03844Y03827*
X03844Y03826*
X03845Y03826*
X03845Y03825*
X03845Y03824*
X03846Y03823*
X03846Y03823*
X03847Y03822*
X03847Y03821*
X03848Y03821*
X03848Y0382*
X03849Y0382*
X0385Y03819*
X03851Y03819*
X03851Y03819*
X03852Y03818*
X03853Y03818*
X03854Y03818*
X03854Y03818*
X03855Y03818*
X03856*
X03857Y03818*
X03858Y03818*
X03859Y03818*
X03859Y03818*
X0386Y03819*
X03861Y03819*
X03862Y03819*
X03862Y0382*
X03863Y0382*
X03864Y03821*
X03864Y03821*
X03865Y03822*
X03865Y03823*
X03866Y03823*
X03866Y03824*
X03867Y03825*
X03867Y03826*
X03867Y03826*
X03867Y03827*
X03867Y03828*
X03868Y03829*
X03868Y0383*
G54D12*
X06191Y03733D02*
D01*
X06191Y03733*
X06191Y03733*
X06191Y03733*
X06191Y03734*
X0619Y03734*
X0619Y03734*
X0619Y03734*
X0619Y03734*
X0619Y03734*
X0619Y03734*
X0619Y03734*
X0619Y03735*
X0619Y03735*
X0619Y03735*
X0619Y03735*
X06189Y03735*
X06189Y03735*
X06189Y03735*
X06189Y03735*
X06189Y03735*
X06189Y03735*
X06189Y03735*
X06189*
X06188Y03735*
X06188Y03735*
X06188Y03735*
X06188Y03735*
X06188Y03735*
X06188Y03735*
X06188Y03735*
X06188Y03735*
X06187Y03735*
X06187Y03735*
X06187Y03734*
X06187Y03734*
X06187Y03734*
X06187Y03734*
X06187Y03734*
X06187Y03734*
X06187Y03734*
X06187Y03734*
X06187Y03733*
X06187Y03733*
X06187Y03733*
X06187Y03733*
X06187Y03733*
X06187Y03733*
X06187Y03733*
X06187Y03732*
X06187Y03732*
X06187Y03732*
X06187Y03732*
X06187Y03732*
X06187Y03732*
X06187Y03732*
X06187Y03732*
X06187Y03732*
X06187Y03731*
X06188Y03731*
X06188Y03731*
X06188Y03731*
X06188Y03731*
X06188Y03731*
X06188Y03731*
X06188Y03731*
X06188Y03731*
X06189Y03731*
X06189*
X06189Y03731*
X06189Y03731*
X06189Y03731*
X06189Y03731*
X06189Y03731*
X06189Y03731*
X0619Y03731*
X0619Y03731*
X0619Y03731*
X0619Y03732*
X0619Y03732*
X0619Y03732*
X0619Y03732*
X0619Y03732*
X0619Y03732*
X0619Y03732*
X0619Y03732*
X06191Y03732*
X06191Y03733*
X06191Y03733*
X06191Y03733*
X06191Y03733*
X01223Y04175D02*
D01*
X01223Y04176*
X01223Y04176*
X01223Y04176*
X01223Y04176*
X01223Y04176*
X01223Y04176*
X01223Y04176*
X01222Y04176*
X01222Y04177*
X01222Y04177*
X01222Y04177*
X01222Y04177*
X01222Y04177*
X01222Y04177*
X01222Y04177*
X01222Y04177*
X01222Y04177*
X01221Y04177*
X01221Y04177*
X01221Y04177*
X01221Y04177*
X01221Y04177*
X01221*
X01221Y04177*
X0122Y04177*
X0122Y04177*
X0122Y04177*
X0122Y04177*
X0122Y04177*
X0122Y04177*
X0122Y04177*
X0122Y04177*
X01219Y04177*
X01219Y04177*
X01219Y04177*
X01219Y04177*
X01219Y04176*
X01219Y04176*
X01219Y04176*
X01219Y04176*
X01219Y04176*
X01219Y04176*
X01219Y04176*
X01219Y04176*
X01219Y04175*
X01219Y04175*
X01219Y04175*
X01219Y04175*
X01219Y04175*
X01219Y04175*
X01219Y04175*
X01219Y04174*
X01219Y04174*
X01219Y04174*
X01219Y04174*
X01219Y04174*
X01219Y04174*
X0122Y04174*
X0122Y04174*
X0122Y04174*
X0122Y04174*
X0122Y04174*
X0122Y04173*
X0122Y04173*
X0122Y04173*
X01221Y04173*
X01221Y04173*
X01221*
X01221Y04173*
X01221Y04173*
X01221Y04173*
X01221Y04173*
X01222Y04174*
X01222Y04174*
X01222Y04174*
X01222Y04174*
X01222Y04174*
X01222Y04174*
X01222Y04174*
X01222Y04174*
X01222Y04174*
X01222Y04174*
X01223Y04174*
X01223Y04175*
X01223Y04175*
X01223Y04175*
X01223Y04175*
X01223Y04175*
X01223Y04175*
X01223Y04175*
X03247Y02866D02*
D01*
X03247Y02866*
X03247Y02865*
X03247Y02865*
X03247Y02865*
X03247Y02865*
X03247Y02865*
X03247Y02865*
X03247Y02865*
X03247Y02864*
X03247Y02864*
X03247Y02864*
X03247Y02864*
X03247Y02864*
X03247Y02864*
X03248Y02864*
X03248Y02864*
X03248Y02864*
X03248Y02864*
X03248Y02864*
X03248Y02864*
X03248Y02864*
X03248Y02864*
X03249*
X03249Y02864*
X03249Y02864*
X03249Y02864*
X03249Y02864*
X03249Y02864*
X03249Y02864*
X0325Y02864*
X0325Y02864*
X0325Y02864*
X0325Y02864*
X0325Y02864*
X0325Y02864*
X0325Y02864*
X0325Y02865*
X0325Y02865*
X0325Y02865*
X0325Y02865*
X0325Y02865*
X0325Y02865*
X0325Y02865*
X0325Y02866*
X0325Y02866*
D01*
X0325Y02866*
X0325Y02866*
X0325Y02866*
X0325Y02866*
X0325Y02866*
X0325Y02866*
X0325Y02867*
X0325Y02867*
X0325Y02867*
X0325Y02867*
X0325Y02867*
X0325Y02867*
X0325Y02867*
X0325Y02867*
X03249Y02867*
X03249Y02867*
X03249Y02867*
X03249Y02868*
X03249Y02868*
X03249Y02868*
X03249Y02868*
X03249Y02868*
X03248*
X03248Y02868*
X03248Y02868*
X03248Y02868*
X03248Y02868*
X03248Y02867*
X03248Y02867*
X03248Y02867*
X03247Y02867*
X03247Y02867*
X03247Y02867*
X03247Y02867*
X03247Y02867*
X03247Y02867*
X03247Y02867*
X03247Y02867*
X03247Y02866*
X03247Y02866*
X03247Y02866*
X03247Y02866*
X03247Y02866*
X03247Y02866*
X03247Y02866*
X05881Y03733D02*
D01*
X05881Y03733*
X05881Y03733*
X05881Y03733*
X05881Y03734*
X0588Y03734*
X0588Y03734*
X0588Y03734*
X0588Y03734*
X0588Y03734*
X0588Y03734*
X0588Y03734*
X0588Y03735*
X0588Y03735*
X0588Y03735*
X0588Y03735*
X05879Y03735*
X05879Y03735*
X05879Y03735*
X05879Y03735*
X05879Y03735*
X05879Y03735*
X05879Y03735*
X05879*
X05878Y03735*
X05878Y03735*
X05878Y03735*
X05878Y03735*
X05878Y03735*
X05878Y03735*
X05878Y03735*
X05878Y03735*
X05877Y03735*
X05877Y03735*
X05877Y03734*
X05877Y03734*
X05877Y03734*
X05877Y03734*
X05877Y03734*
X05877Y03734*
X05877Y03734*
X05877Y03734*
X05877Y03733*
X05877Y03733*
X05877Y03733*
X05877Y03733*
X05877Y03733*
X05877Y03733*
X05877Y03733*
X05877Y03732*
X05877Y03732*
X05877Y03732*
X05877Y03732*
X05877Y03732*
X05877Y03732*
X05877Y03732*
X05877Y03732*
X05877Y03732*
X05877Y03731*
X05878Y03731*
X05878Y03731*
X05878Y03731*
X05878Y03731*
X05878Y03731*
X05878Y03731*
X05878Y03731*
X05878Y03731*
X05879Y03731*
X05879*
X05879Y03731*
X05879Y03731*
X05879Y03731*
X05879Y03731*
X05879Y03731*
X05879Y03731*
X0588Y03731*
X0588Y03731*
X0588Y03731*
X0588Y03732*
X0588Y03732*
X0588Y03732*
X0588Y03732*
X0588Y03732*
X0588Y03732*
X0588Y03732*
X0588Y03732*
X05881Y03732*
X05881Y03733*
X05881Y03733*
X05881Y03733*
X05881Y03733*
X06196Y03598D02*
D01*
X06196Y03598*
X06196Y03598*
X06196Y03598*
X06196Y03599*
X06195Y03599*
X06195Y03599*
X06195Y03599*
X06195Y03599*
X06195Y03599*
X06195Y03599*
X06195Y03599*
X06195Y036*
X06195Y036*
X06195Y036*
X06195Y036*
X06194Y036*
X06194Y036*
X06194Y036*
X06194Y036*
X06194Y036*
X06194Y036*
X06194Y036*
X06194*
X06193Y036*
X06193Y036*
X06193Y036*
X06193Y036*
X06193Y036*
X06193Y036*
X06193Y036*
X06193Y036*
X06192Y036*
X06192Y036*
X06192Y03599*
X06192Y03599*
X06192Y03599*
X06192Y03599*
X06192Y03599*
X06192Y03599*
X06192Y03599*
X06192Y03599*
X06192Y03598*
X06192Y03598*
X06192Y03598*
X06192Y03598*
X06192Y03598*
X06192Y03598*
X06192Y03598*
X06192Y03597*
X06192Y03597*
X06192Y03597*
X06192Y03597*
X06192Y03597*
X06192Y03597*
X06192Y03597*
X06192Y03597*
X06192Y03597*
X06192Y03596*
X06193Y03596*
X06193Y03596*
X06193Y03596*
X06193Y03596*
X06193Y03596*
X06193Y03596*
X06193Y03596*
X06193Y03596*
X06194Y03596*
X06194*
X06194Y03596*
X06194Y03596*
X06194Y03596*
X06194Y03596*
X06194Y03596*
X06194Y03596*
X06195Y03596*
X06195Y03596*
X06195Y03596*
X06195Y03597*
X06195Y03597*
X06195Y03597*
X06195Y03597*
X06195Y03597*
X06195Y03597*
X06195Y03597*
X06195Y03597*
X06196Y03597*
X06196Y03598*
X06196Y03598*
X06196Y03598*
X06196Y03598*
X04255Y03631D02*
D01*
X04255Y03632*
X04255Y03632*
X04255Y03632*
X04255Y03632*
X04255Y03632*
X04255Y03632*
X04255Y03632*
X04255Y03632*
X04255Y03633*
X04255Y03633*
X04255Y03633*
X04255Y03633*
X04255Y03633*
X04255Y03633*
X04254Y03633*
X04254Y03633*
X04254Y03633*
X04254Y03633*
X04254Y03633*
X04254Y03633*
X04254Y03633*
X04254Y03633*
X04253*
X04253Y03633*
X04253Y03633*
X04253Y03633*
X04253Y03633*
X04253Y03633*
X04253Y03633*
X04252Y03633*
X04252Y03633*
X04252Y03633*
X04252Y03633*
X04252Y03633*
X04252Y03633*
X04252Y03633*
X04252Y03632*
X04252Y03632*
X04252Y03632*
X04252Y03632*
X04252Y03632*
X04252Y03632*
X04251Y03632*
X04251Y03632*
X04251Y03631*
X04251Y03631*
X04251Y03631*
X04252Y03631*
X04252Y03631*
X04252Y03631*
X04252Y03631*
X04252Y0363*
X04252Y0363*
X04252Y0363*
X04252Y0363*
X04252Y0363*
X04252Y0363*
X04252Y0363*
X04252Y0363*
X04252Y0363*
X04253Y0363*
X04253Y0363*
X04253Y0363*
X04253Y03629*
X04253Y03629*
X04253Y03629*
X04253Y03629*
X04254*
X04254Y03629*
X04254Y03629*
X04254Y03629*
X04254Y0363*
X04254Y0363*
X04254Y0363*
X04254Y0363*
X04255Y0363*
X04255Y0363*
X04255Y0363*
X04255Y0363*
X04255Y0363*
X04255Y0363*
X04255Y0363*
X04255Y0363*
X04255Y03631*
X04255Y03631*
X04255Y03631*
X04255Y03631*
X04255Y03631*
X04255Y03631*
X04255Y03631*
X0362Y03931D02*
D01*
X0362Y03931*
X0362Y03931*
X0362Y03931*
X0362Y03931*
X0362Y03931*
X0362Y03932*
X0362Y03932*
X0362Y03932*
X03619Y03932*
X03619Y03932*
X03619Y03932*
X03619Y03932*
X03619Y03932*
X03619Y03932*
X03619Y03932*
X03619Y03933*
X03619Y03933*
X03618Y03933*
X03618Y03933*
X03618Y03933*
X03618Y03933*
X03618Y03933*
X03618*
X03618Y03933*
X03618Y03933*
X03617Y03933*
X03617Y03933*
X03617Y03933*
X03617Y03933*
X03617Y03932*
X03617Y03932*
X03617Y03932*
X03617Y03932*
X03616Y03932*
X03616Y03932*
X03616Y03932*
X03616Y03932*
X03616Y03932*
X03616Y03932*
X03616Y03931*
X03616Y03931*
X03616Y03931*
X03616Y03931*
X03616Y03931*
X03616Y03931*
X03616Y03931*
X03616Y0393*
X03616Y0393*
X03616Y0393*
X03616Y0393*
X03616Y0393*
X03616Y0393*
X03616Y0393*
X03616Y0393*
X03616Y03929*
X03616Y03929*
X03617Y03929*
X03617Y03929*
X03617Y03929*
X03617Y03929*
X03617Y03929*
X03617Y03929*
X03617Y03929*
X03617Y03929*
X03618Y03929*
X03618Y03929*
X03618Y03929*
X03618*
X03618Y03929*
X03618Y03929*
X03618Y03929*
X03618Y03929*
X03619Y03929*
X03619Y03929*
X03619Y03929*
X03619Y03929*
X03619Y03929*
X03619Y03929*
X03619Y03929*
X03619Y03929*
X03619Y0393*
X0362Y0393*
X0362Y0393*
X0362Y0393*
X0362Y0393*
X0362Y0393*
X0362Y0393*
X0362Y0393*
X0362Y03931*
X0362Y03931*
X03563Y03705D02*
D01*
X03563Y03706*
X03563Y03706*
X03563Y03706*
X03563Y03706*
X03563Y03706*
X03563Y03706*
X03563Y03706*
X03562Y03706*
X03562Y03707*
X03562Y03707*
X03562Y03707*
X03562Y03707*
X03562Y03707*
X03562Y03707*
X03562Y03707*
X03562Y03707*
X03562Y03707*
X03561Y03707*
X03561Y03707*
X03561Y03707*
X03561Y03707*
X03561Y03707*
X03561*
X03561Y03707*
X0356Y03707*
X0356Y03707*
X0356Y03707*
X0356Y03707*
X0356Y03707*
X0356Y03707*
X0356Y03707*
X0356Y03707*
X03559Y03707*
X03559Y03707*
X03559Y03707*
X03559Y03707*
X03559Y03706*
X03559Y03706*
X03559Y03706*
X03559Y03706*
X03559Y03706*
X03559Y03706*
X03559Y03706*
X03559Y03706*
X03559Y03705*
X03559Y03705*
X03559Y03705*
X03559Y03705*
X03559Y03705*
X03559Y03705*
X03559Y03705*
X03559Y03704*
X03559Y03704*
X03559Y03704*
X03559Y03704*
X03559Y03704*
X03559Y03704*
X0356Y03704*
X0356Y03704*
X0356Y03704*
X0356Y03704*
X0356Y03704*
X0356Y03703*
X0356Y03703*
X0356Y03703*
X03561Y03703*
X03561Y03703*
X03561*
X03561Y03703*
X03561Y03703*
X03561Y03703*
X03561Y03703*
X03562Y03704*
X03562Y03704*
X03562Y03704*
X03562Y03704*
X03562Y03704*
X03562Y03704*
X03562Y03704*
X03562Y03704*
X03562Y03704*
X03562Y03704*
X03563Y03704*
X03563Y03705*
X03563Y03705*
X03563Y03705*
X03563Y03705*
X03563Y03705*
X03563Y03705*
X03563Y03705*
X00618Y04175D02*
D01*
X00618Y04176*
X00618Y04176*
X00618Y04176*
X00618Y04176*
X00618Y04176*
X00618Y04176*
X00618Y04176*
X00617Y04176*
X00617Y04177*
X00617Y04177*
X00617Y04177*
X00617Y04177*
X00617Y04177*
X00617Y04177*
X00617Y04177*
X00617Y04177*
X00617Y04177*
X00616Y04177*
X00616Y04177*
X00616Y04177*
X00616Y04177*
X00616Y04177*
X00616*
X00616Y04177*
X00615Y04177*
X00615Y04177*
X00615Y04177*
X00615Y04177*
X00615Y04177*
X00615Y04177*
X00615Y04177*
X00615Y04177*
X00614Y04177*
X00614Y04177*
X00614Y04177*
X00614Y04177*
X00614Y04176*
X00614Y04176*
X00614Y04176*
X00614Y04176*
X00614Y04176*
X00614Y04176*
X00614Y04176*
X00614Y04176*
X00614Y04175*
X00614Y04175*
X00614Y04175*
X00614Y04175*
X00614Y04175*
X00614Y04175*
X00614Y04175*
X00614Y04174*
X00614Y04174*
X00614Y04174*
X00614Y04174*
X00614Y04174*
X00614Y04174*
X00615Y04174*
X00615Y04174*
X00615Y04174*
X00615Y04174*
X00615Y04174*
X00615Y04173*
X00615Y04173*
X00615Y04173*
X00616Y04173*
X00616Y04173*
X00616*
X00616Y04173*
X00616Y04173*
X00616Y04173*
X00616Y04173*
X00617Y04174*
X00617Y04174*
X00617Y04174*
X00617Y04174*
X00617Y04174*
X00617Y04174*
X00617Y04174*
X00617Y04174*
X00617Y04174*
X00617Y04174*
X00618Y04174*
X00618Y04175*
X00618Y04175*
X00618Y04175*
X00618Y04175*
X00618Y04175*
X00618Y04175*
X00618Y04175*
X00819D02*
D01*
X00819Y04176*
X00819Y04176*
X00819Y04176*
X00819Y04176*
X00819Y04176*
X00819Y04176*
X00819Y04176*
X00819Y04176*
X00819Y04177*
X00819Y04177*
X00819Y04177*
X00819Y04177*
X00819Y04177*
X00819Y04177*
X00818Y04177*
X00818Y04177*
X00818Y04177*
X00818Y04177*
X00818Y04177*
X00818Y04177*
X00818Y04177*
X00818Y04177*
X00817*
X00817Y04177*
X00817Y04177*
X00817Y04177*
X00817Y04177*
X00817Y04177*
X00817Y04177*
X00816Y04177*
X00816Y04177*
X00816Y04177*
X00816Y04177*
X00816Y04177*
X00816Y04177*
X00816Y04177*
X00816Y04176*
X00816Y04176*
X00816Y04176*
X00816Y04176*
X00816Y04176*
X00816Y04176*
X00816Y04176*
X00815Y04176*
X00815Y04175*
X00815Y04175*
X00816Y04175*
X00816Y04175*
X00816Y04175*
X00816Y04175*
X00816Y04175*
X00816Y04174*
X00816Y04174*
X00816Y04174*
X00816Y04174*
X00816Y04174*
X00816Y04174*
X00816Y04174*
X00816Y04174*
X00816Y04174*
X00817Y04174*
X00817Y04174*
X00817Y04173*
X00817Y04173*
X00817Y04173*
X00817Y04173*
X00817Y04173*
X00818*
X00818Y04173*
X00818Y04173*
X00818Y04173*
X00818Y04173*
X00818Y04174*
X00818Y04174*
X00818Y04174*
X00819Y04174*
X00819Y04174*
X00819Y04174*
X00819Y04174*
X00819Y04174*
X00819Y04174*
X00819Y04174*
X00819Y04174*
X00819Y04175*
X00819Y04175*
X00819Y04175*
X00819Y04175*
X00819Y04175*
X00819Y04175*
X00819Y04175*
X01021D02*
D01*
X01021Y04176*
X01021Y04176*
X01021Y04176*
X01021Y04176*
X01021Y04176*
X01021Y04176*
X01021Y04176*
X01021Y04176*
X01021Y04177*
X01021Y04177*
X01021Y04177*
X0102Y04177*
X0102Y04177*
X0102Y04177*
X0102Y04177*
X0102Y04177*
X0102Y04177*
X0102Y04177*
X0102Y04177*
X01019Y04177*
X01019Y04177*
X01019Y04177*
X01019*
X01019Y04177*
X01019Y04177*
X01019Y04177*
X01019Y04177*
X01018Y04177*
X01018Y04177*
X01018Y04177*
X01018Y04177*
X01018Y04177*
X01018Y04177*
X01018Y04177*
X01018Y04177*
X01018Y04177*
X01017Y04176*
X01017Y04176*
X01017Y04176*
X01017Y04176*
X01017Y04176*
X01017Y04176*
X01017Y04176*
X01017Y04176*
X01017Y04175*
X01017Y04175*
X01017Y04175*
X01017Y04175*
X01017Y04175*
X01017Y04175*
X01017Y04175*
X01017Y04174*
X01017Y04174*
X01018Y04174*
X01018Y04174*
X01018Y04174*
X01018Y04174*
X01018Y04174*
X01018Y04174*
X01018Y04174*
X01018Y04174*
X01018Y04174*
X01019Y04173*
X01019Y04173*
X01019Y04173*
X01019Y04173*
X01019Y04173*
X01019*
X01019Y04173*
X01019Y04173*
X0102Y04173*
X0102Y04173*
X0102Y04174*
X0102Y04174*
X0102Y04174*
X0102Y04174*
X0102Y04174*
X0102Y04174*
X01021Y04174*
X01021Y04174*
X01021Y04174*
X01021Y04174*
X01021Y04174*
X01021Y04175*
X01021Y04175*
X01021Y04175*
X01021Y04175*
X01021Y04175*
X01021Y04175*
X01021Y04175*
X03278Y02846D02*
Y02854D01*
X03258D02*
X03278D01*
Y02775D02*
Y02783D01*
X03258Y02775D02*
X03278D01*
X03199D02*
X03219D01*
X03199D02*
Y02783D01*
Y02846D02*
Y02854D01*
X03219*
G54D13*
X06679Y03131D02*
D01*
X06679Y03131*
X06679Y03131*
X06679Y03132*
X06679Y03132*
X06679Y03132*
X06679Y03133*
X06679Y03133*
X06679Y03133*
X06678Y03133*
X06678Y03134*
X06678Y03134*
X06678Y03134*
X06677Y03135*
X06677Y03135*
X06677Y03135*
X06677Y03135*
X06676Y03135*
X06676Y03135*
X06676Y03135*
X06675Y03135*
X06675Y03136*
X06675Y03136*
X06674*
X06674Y03136*
X06673Y03135*
X06673Y03135*
X06673Y03135*
X06672Y03135*
X06672Y03135*
X06672Y03135*
X06672Y03135*
X06671Y03135*
X06671Y03134*
X06671Y03134*
X06671Y03134*
X0667Y03133*
X0667Y03133*
X0667Y03133*
X0667Y03133*
X0667Y03132*
X0667Y03132*
X06669Y03132*
X06669Y03131*
X06669Y03131*
X06669Y03131*
X06669Y0313*
X06669Y0313*
X06669Y0313*
X0667Y03129*
X0667Y03129*
X0667Y03129*
X0667Y03128*
X0667Y03128*
X0667Y03128*
X06671Y03127*
X06671Y03127*
X06671Y03127*
X06671Y03127*
X06672Y03126*
X06672Y03126*
X06672Y03126*
X06672Y03126*
X06673Y03126*
X06673Y03126*
X06673Y03126*
X06674Y03126*
X06674Y03126*
X06675*
X06675Y03126*
X06675Y03126*
X06676Y03126*
X06676Y03126*
X06676Y03126*
X06677Y03126*
X06677Y03126*
X06677Y03126*
X06677Y03127*
X06678Y03127*
X06678Y03127*
X06678Y03127*
X06678Y03128*
X06679Y03128*
X06679Y03128*
X06679Y03129*
X06679Y03129*
X06679Y03129*
X06679Y0313*
X06679Y0313*
X06679Y0313*
X06679Y03131*
X04129Y01599D02*
D01*
X04129Y01599*
X04129Y016*
X04129Y016*
X04129Y016*
X04129Y01601*
X04129Y01601*
X04129Y01601*
X04129Y01602*
X04128Y01602*
X04128Y01602*
X04128Y01603*
X04128Y01603*
X04127Y01603*
X04127Y01603*
X04127Y01603*
X04127Y01604*
X04126Y01604*
X04126Y01604*
X04126Y01604*
X04125Y01604*
X04125Y01604*
X04124Y01604*
X04124*
X04124Y01604*
X04123Y01604*
X04123Y01604*
X04123Y01604*
X04122Y01604*
X04122Y01604*
X04122Y01603*
X04122Y01603*
X04121Y01603*
X04121Y01603*
X04121Y01603*
X0412Y01602*
X0412Y01602*
X0412Y01602*
X0412Y01601*
X0412Y01601*
X0412Y01601*
X0412Y016*
X04119Y016*
X04119Y016*
X04119Y01599*
X04119Y01599*
X04119Y01599*
X04119Y01598*
X04119Y01598*
X0412Y01598*
X0412Y01597*
X0412Y01597*
X0412Y01597*
X0412Y01596*
X0412Y01596*
X0412Y01596*
X04121Y01596*
X04121Y01595*
X04121Y01595*
X04122Y01595*
X04122Y01595*
X04122Y01595*
X04122Y01594*
X04123Y01594*
X04123Y01594*
X04123Y01594*
X04124Y01594*
X04124Y01594*
X04124*
X04125Y01594*
X04125Y01594*
X04126Y01594*
X04126Y01594*
X04126Y01594*
X04127Y01595*
X04127Y01595*
X04127Y01595*
X04127Y01595*
X04128Y01595*
X04128Y01596*
X04128Y01596*
X04128Y01596*
X04129Y01596*
X04129Y01597*
X04129Y01597*
X04129Y01597*
X04129Y01598*
X04129Y01598*
X04129Y01598*
X04129Y01599*
X04129Y01599*
X0021Y02829D02*
D01*
X0021Y02834*
X00209Y02838*
X00209Y02842*
X00208Y02846*
X00206Y0285*
X00205Y02854*
X00203Y02858*
X00201Y02862*
X00198Y02865*
X00196Y02869*
X00193Y02872*
X0019Y02875*
X00187Y02878*
X00183Y0288*
X0018Y02882*
X00176Y02884*
X00172Y02886*
X00168Y02887*
X00164Y02889*
X0016Y0289*
X00155Y0289*
X00151Y0289*
X00147*
X00143Y0289*
X00138Y0289*
X00134Y02889*
X0013Y02887*
X00126Y02886*
X00122Y02884*
X00118Y02882*
X00115Y0288*
X00111Y02878*
X00108Y02875*
X00105Y02872*
X00102Y02869*
X001Y02865*
X00097Y02862*
X00095Y02858*
X00093Y02854*
X00092Y0285*
X0009Y02846*
X00089Y02842*
X00089Y02838*
X00088Y02834*
X00088Y02829*
X00088Y02825*
X00089Y02821*
X00089Y02817*
X0009Y02813*
X00092Y02809*
X00093Y02805*
X00095Y02801*
X00097Y02797*
X001Y02794*
X00102Y0279*
X00105Y02787*
X00108Y02784*
X00111Y02781*
X00115Y02779*
X00119Y02777*
X00122Y02775*
X00126Y02773*
X0013Y02771*
X00134Y0277*
X00138Y02769*
X00143Y02769*
X00147Y02768*
X00151*
X00155Y02769*
X0016Y02769*
X00164Y0277*
X00168Y02771*
X00172Y02773*
X00176Y02775*
X0018Y02777*
X00183Y02779*
X00187Y02781*
X0019Y02784*
X00193Y02787*
X00196Y0279*
X00198Y02794*
X00201Y02797*
X00203Y02801*
X00205Y02805*
X00206Y02809*
X00208Y02813*
X00209Y02817*
X00209Y02821*
X0021Y02825*
X0021Y02829*
Y03853D02*
D01*
X0021Y03857*
X00209Y03862*
X00209Y03866*
X00208Y0387*
X00206Y03874*
X00205Y03878*
X00203Y03882*
X00201Y03885*
X00198Y03889*
X00196Y03892*
X00193Y03895*
X0019Y03898*
X00187Y03901*
X00183Y03904*
X0018Y03906*
X00176Y03908*
X00172Y0391*
X00168Y03911*
X00164Y03912*
X0016Y03913*
X00155Y03914*
X00151Y03914*
X00147*
X00143Y03914*
X00138Y03913*
X00134Y03912*
X0013Y03911*
X00126Y0391*
X00122Y03908*
X00118Y03906*
X00115Y03904*
X00111Y03901*
X00108Y03898*
X00105Y03895*
X00102Y03892*
X001Y03889*
X00097Y03885*
X00095Y03882*
X00093Y03878*
X00092Y03874*
X0009Y0387*
X00089Y03866*
X00089Y03862*
X00088Y03857*
X00088Y03853*
X00088Y03849*
X00089Y03845*
X00089Y0384*
X0009Y03836*
X00092Y03832*
X00093Y03828*
X00095Y03824*
X00097Y03821*
X001Y03817*
X00102Y03814*
X00105Y03811*
X00108Y03808*
X00111Y03805*
X00115Y03802*
X00119Y038*
X00122Y03798*
X00126Y03796*
X0013Y03795*
X00134Y03794*
X00138Y03793*
X00143Y03792*
X00147Y03792*
X00151*
X00155Y03792*
X0016Y03793*
X00164Y03794*
X00168Y03795*
X00172Y03796*
X00176Y03798*
X0018Y038*
X00183Y03802*
X00187Y03805*
X0019Y03808*
X00193Y03811*
X00196Y03814*
X00198Y03817*
X00201Y03821*
X00203Y03824*
X00205Y03828*
X00206Y03832*
X00208Y03836*
X00209Y0384*
X00209Y03845*
X0021Y03849*
X0021Y03853*
X02592D02*
D01*
X02592Y03857*
X02591Y03862*
X02591Y03866*
X0259Y0387*
X02588Y03874*
X02587Y03878*
X02585Y03882*
X02583Y03885*
X0258Y03889*
X02578Y03892*
X02575Y03895*
X02572Y03898*
X02568Y03901*
X02565Y03904*
X02561Y03906*
X02558Y03908*
X02554Y0391*
X0255Y03911*
X02546Y03912*
X02541Y03913*
X02537Y03914*
X02533Y03914*
X02529*
X02525Y03914*
X0252Y03913*
X02516Y03912*
X02512Y03911*
X02508Y0391*
X02504Y03908*
X025Y03906*
X02497Y03904*
X02493Y03901*
X0249Y03898*
X02487Y03895*
X02484Y03892*
X02482Y03889*
X02479Y03885*
X02477Y03882*
X02475Y03878*
X02474Y03874*
X02472Y0387*
X02471Y03866*
X0247Y03862*
X0247Y03857*
X0247Y03853*
X0247Y03849*
X0247Y03845*
X02471Y0384*
X02472Y03836*
X02474Y03832*
X02475Y03828*
X02477Y03824*
X02479Y03821*
X02482Y03817*
X02484Y03814*
X02487Y03811*
X0249Y03808*
X02493Y03805*
X02497Y03802*
X025Y038*
X02504Y03798*
X02508Y03796*
X02512Y03795*
X02516Y03794*
X0252Y03793*
X02525Y03792*
X02529Y03792*
X02533*
X02537Y03792*
X02541Y03793*
X02546Y03794*
X0255Y03795*
X02554Y03796*
X02558Y03798*
X02561Y038*
X02565Y03802*
X02568Y03805*
X02572Y03808*
X02575Y03811*
X02578Y03814*
X0258Y03817*
X02583Y03821*
X02585Y03824*
X02587Y03828*
X02588Y03832*
X0259Y03836*
X02591Y0384*
X02591Y03845*
X02592Y03849*
X02592Y03853*
Y02829D02*
D01*
X02592Y02834*
X02591Y02838*
X02591Y02842*
X0259Y02846*
X02588Y0285*
X02587Y02854*
X02585Y02858*
X02583Y02862*
X0258Y02865*
X02578Y02869*
X02575Y02872*
X02572Y02875*
X02568Y02878*
X02565Y0288*
X02561Y02882*
X02558Y02884*
X02554Y02886*
X0255Y02887*
X02546Y02889*
X02541Y0289*
X02537Y0289*
X02533Y0289*
X02529*
X02525Y0289*
X0252Y0289*
X02516Y02889*
X02512Y02887*
X02508Y02886*
X02504Y02884*
X025Y02882*
X02497Y0288*
X02493Y02878*
X0249Y02875*
X02487Y02872*
X02484Y02869*
X02482Y02865*
X02479Y02862*
X02477Y02858*
X02475Y02854*
X02474Y0285*
X02472Y02846*
X02471Y02842*
X0247Y02838*
X0247Y02834*
X0247Y02829*
X0247Y02825*
X0247Y02821*
X02471Y02817*
X02472Y02813*
X02474Y02809*
X02475Y02805*
X02477Y02801*
X02479Y02797*
X02482Y02794*
X02484Y0279*
X02487Y02787*
X0249Y02784*
X02493Y02781*
X02497Y02779*
X025Y02777*
X02504Y02775*
X02508Y02773*
X02512Y02771*
X02516Y0277*
X0252Y02769*
X02525Y02769*
X02529Y02768*
X02533*
X02537Y02769*
X02541Y02769*
X02546Y0277*
X0255Y02771*
X02554Y02773*
X02558Y02775*
X02561Y02777*
X02565Y02779*
X02568Y02781*
X02572Y02784*
X02575Y02787*
X02578Y0279*
X0258Y02794*
X02583Y02797*
X02585Y02801*
X02587Y02805*
X02588Y02809*
X0259Y02813*
X02591Y02817*
X02591Y02821*
X02592Y02825*
X02592Y02829*
X03778Y02689D02*
X05778D01*
X03778Y00689D02*
Y02689D01*
Y00689D02*
X05778D01*
Y02689*
X06364Y03351D02*
X06534D01*
X06364Y03131D02*
Y03351D01*
Y03131D02*
X06534D01*
Y03351*
X06931Y02348D02*
Y02874D01*
X06427Y02348D02*
X06931D01*
X06427D02*
Y02874D01*
X06931*
X06067Y01388D02*
Y01914D01*
X06571*
Y01388D02*
Y01914D01*
X06067Y01388D02*
X06571D01*
X00018Y02716D02*
X02662D01*
X00018D02*
Y03966D01*
X02662*
Y02716D02*
Y03966D01*
X02841Y03381D02*
Y03356D01*
X02846Y03351*
X02856*
X02861Y03356*
Y03381*
X02871Y03376D02*
X02876Y03381D01*
X02886*
X02891Y03376*
Y03371*
X02886Y03366*
X02881*
X02886*
X02891Y03361*
Y03356*
X02886Y03351*
X02876*
X02871Y03356*
X02402Y04126D02*
Y04106D01*
Y04116*
X02462*
X02452Y04126*
X03984Y03973D02*
X03964D01*
X03974*
Y03913*
X03984Y03923*
X04137Y02522D02*
Y02497D01*
X04142Y02492*
X04152*
X04157Y02497*
Y02522*
X04167Y02492D02*
X04177D01*
X04172*
Y02522*
X04167Y02517*
X04192D02*
X04197Y02522D01*
X04207*
X04212Y02517*
Y02497*
X04207Y02492*
X04197*
X04192Y02497*
Y02517*
X04222Y02492D02*
Y02512D01*
X04232Y02522*
X04242Y02512*
Y02492*
Y02507*
X04222*
X04252Y02522D02*
Y02492D01*
X04272*
X00891Y00772D02*
Y00802D01*
X00906*
X00911Y00797*
Y00787*
X00906Y00782*
X00891*
X00901D02*
X00911Y00772D01*
X00921Y00797D02*
X00926Y00802D01*
X00936*
X00941Y00797*
Y00792*
X00936Y00787*
X00931*
X00936*
X00941Y00782*
Y00777*
X00936Y00772*
X00926*
X00921Y00777*
X00971Y00802D02*
X00961Y00797D01*
X00951Y00787*
Y00777*
X00956Y00772*
X00966*
X00971Y00777*
Y00782*
X00966Y00787*
X00951*
X04458Y0391D02*
Y0388D01*
X04473*
X04478Y03885*
Y0389*
X04473Y03895*
X04458*
X04473*
X04478Y039*
Y03905*
X04473Y0391*
X04458*
X04488D02*
X04508D01*
X04498*
Y0388*
X04518D02*
X04528D01*
X04523*
Y0391*
X04518Y03905*
X03191Y02946D02*
X03201D01*
X03196*
Y02916*
X03191*
X03201*
X03236Y02941D02*
X03231Y02946D01*
X03221*
X03216Y02941*
Y02921*
X03221Y02916*
X03231*
X03236Y02921*
X03246Y02941D02*
X03251Y02946D01*
X03261*
X03266Y02941*
Y02936*
X03256Y02926*
Y02921D02*
Y02916D01*
X03543Y02184D02*
X03563D01*
X03553*
Y02244*
X03543Y02234*
X02108Y02409D02*
X02068D01*
X02108Y02449*
Y02459*
X02098Y02469*
X02078*
X02068Y02459*
X01668Y02234D02*
X01678Y02244D01*
X01698*
X01708Y02234*
Y02224*
X01698Y02214*
X01688*
X01698*
X01708Y02204*
Y02194*
X01698Y02184*
X01678*
X01668Y02194*
X02098Y00934D02*
Y00994D01*
X02068Y00964*
X02108*
X02373Y03008D02*
Y03038D01*
X02388*
X02393Y03033*
Y03023*
X02388Y03018*
X02373*
X02383D02*
X02393Y03008D01*
X02403D02*
X02413D01*
X02408*
Y03038*
X02403Y03033*
X02428Y03038D02*
X02448D01*
Y03033*
X02428Y03013*
Y03008*
X01069Y02269D02*
Y02299D01*
X01084*
X01089Y02294*
Y02284*
X01084Y02279*
X01069*
X01079D02*
X01089Y02269D01*
X01099D02*
X01109D01*
X01104*
Y02299*
X01099Y02294*
X01139Y02269D02*
Y02299D01*
X01124Y02284*
X01144*
X01069Y01732D02*
Y01762D01*
X01084*
X01089Y01757*
Y01747*
X01084Y01742*
X01069*
X01079D02*
X01089Y01732D01*
X01099D02*
X01109D01*
X01104*
Y01762*
X01099Y01757*
X01144Y01762D02*
X01124D01*
Y01747*
X01134Y01752*
X01139*
X01144Y01747*
Y01737*
X01139Y01732*
X01129*
X01124Y01737*
X01048Y01218D02*
Y01248D01*
X01063*
X01068Y01243*
Y01233*
X01063Y01228*
X01048*
X01058D02*
X01068Y01218D01*
X01078D02*
X01088D01*
X01083*
Y01248*
X01078Y01243*
X01123Y01248D02*
X01113Y01243D01*
X01103Y01233*
Y01223*
X01108Y01218*
X01118*
X01123Y01223*
Y01228*
X01118Y01233*
X01103*
G54D14*
X02869Y03861D02*
D01*
X02869Y03862*
X02869Y03864*
X02869Y03866*
X02868Y03867*
X02868Y03869*
X02867Y03871*
X02866Y03872*
X02866Y03874*
X02865Y03875*
X02863Y03877*
X02862Y03878*
X02861Y03879*
X0286Y0388*
X02858Y03881*
X02857Y03882*
X02855Y03883*
X02854Y03884*
X02852Y03884*
X0285Y03885*
X02849Y03885*
X02847Y03885*
X02845Y03886*
X02843*
X02842Y03885*
X0284Y03885*
X02838Y03885*
X02837Y03884*
X02835Y03884*
X02833Y03883*
X02832Y03882*
X0283Y03881*
X02829Y0388*
X02828Y03879*
X02826Y03878*
X02825Y03877*
X02824Y03875*
X02823Y03874*
X02822Y03872*
X02822Y03871*
X02821Y03869*
X0282Y03867*
X0282Y03866*
X0282Y03864*
X02819Y03862*
X02819Y03861*
X02819Y03859*
X0282Y03857*
X0282Y03855*
X0282Y03854*
X02821Y03852*
X02822Y0385*
X02822Y03849*
X02823Y03847*
X02824Y03846*
X02825Y03845*
X02826Y03843*
X02828Y03842*
X02829Y03841*
X0283Y0384*
X02832Y03839*
X02833Y03838*
X02835Y03837*
X02837Y03837*
X02838Y03836*
X0284Y03836*
X02842Y03836*
X02843Y03836*
X02845*
X02847Y03836*
X02849Y03836*
X0285Y03836*
X02852Y03837*
X02854Y03837*
X02855Y03838*
X02857Y03839*
X02858Y0384*
X0286Y03841*
X02861Y03842*
X02862Y03843*
X02863Y03845*
X02865Y03846*
X02866Y03847*
X02866Y03849*
X02867Y0385*
X02868Y03852*
X02868Y03854*
X02869Y03855*
X02869Y03857*
X02869Y03859*
X02869Y03861*
X02812Y02905D02*
Y03318D01*
X03056Y02905D02*
Y03318D01*
X02812D02*
X03056D01*
X02812Y02905D02*
X03056D01*
X03426Y03679D02*
X03444D01*
X03426D02*
Y03718D01*
X03495Y03679D02*
X03513D01*
Y03718*
X01675Y04013D02*
X01801D01*
X01675Y0421D02*
X01801D01*
Y04013D02*
Y0421D01*
X01675Y04013D02*
Y0421D01*
X0633Y03663D02*
Y03668D01*
X06208Y03663D02*
Y03668D01*
X0633Y03733D02*
Y03738D01*
X06208Y03733D02*
Y03738D01*
Y03663D02*
X0633D01*
X06208Y03738D02*
X0633D01*
X02744Y03903D02*
X02906D01*
X03383D02*
X03544D01*
X03383Y04268D02*
X03544D01*
X02744D02*
X02906D01*
X03544Y03903D02*
Y04268D01*
X02744Y03903D02*
Y04268D01*
X04132Y00857D02*
Y02457D01*
Y00857D02*
X05522D01*
Y02457*
X04132D02*
X05522D01*
X00923Y00732D02*
X00938D01*
X00923Y00704D02*
X00938D01*
X04897Y02703D02*
X04921D01*
X04909Y02691D02*
Y02715D01*
X04584Y02812D02*
X04812D01*
X05006D02*
X05234D01*
Y03957*
X04584D02*
X04812D01*
X05006D02*
X05234D01*
X04584Y02812D02*
Y03957D01*
X00903Y00782D02*
X01186D01*
X00903Y0103D02*
X01186D01*
Y00782D02*
Y00828D01*
X00903Y00782D02*
Y00828D01*
X01186Y00983D02*
Y0103D01*
X00903Y00983D02*
Y0103D01*
X0602Y03663D02*
Y03668D01*
X05898Y03663D02*
Y03668D01*
X0602Y03733D02*
Y03738D01*
X05898Y03733D02*
Y03738D01*
Y03663D02*
X0602D01*
X05898Y03738D02*
X0602D01*
X06213Y03603D02*
X06335D01*
X06213Y03528D02*
X06335D01*
X06213Y03598D02*
Y03603D01*
X06335Y03598D02*
Y03603D01*
X06213Y03528D02*
Y03533D01*
X06335Y03528D02*
Y03533D01*
X02791Y03679D02*
X02809D01*
X02791D02*
Y03718D01*
X0286Y03679D02*
X02878D01*
Y03718*
X02676Y03679D02*
X02694D01*
X02676D02*
Y03718D01*
X02745Y03679D02*
X02763D01*
Y03718*
X03201Y03679D02*
X03219D01*
X03201D02*
Y03718D01*
X0327Y03679D02*
X03288D01*
Y03718*
X00903Y02033D02*
Y0208D01*
X01186Y02033D02*
Y0208D01*
X00903Y01832D02*
Y01878D01*
X01186Y01832D02*
Y01878D01*
X00903Y0208D02*
X01186D01*
X00903Y01832D02*
X01186D01*
X00903Y02558D02*
Y02605D01*
X01186Y02558D02*
Y02605D01*
X00903Y02357D02*
Y02403D01*
X01186Y02357D02*
Y02403D01*
X00903Y02605D02*
X01186D01*
X00903Y02357D02*
X01186D01*
X00903Y01307D02*
X01186D01*
X00903Y01555D02*
X01186D01*
Y01307D02*
Y01353D01*
X00903Y01307D02*
Y01353D01*
X01186Y01508D02*
Y01555D01*
X00903Y01508D02*
Y01555D01*
X03816Y03672D02*
X03942D01*
X03816Y03869D02*
X03942D01*
Y03672D02*
Y03869D01*
X03816Y03672D02*
Y03869D01*
X01332Y04104D02*
Y0412D01*
X0136Y04104D02*
Y0412D01*
Y04D02*
Y04015D01*
X01332Y04D02*
Y04015D01*
X02137Y04037D02*
Y04053D01*
X02165Y04037D02*
Y04053D01*
X02198Y04037D02*
Y04053D01*
X02226Y04037D02*
Y04053D01*
X02374Y02921D02*
Y02937D01*
X02401Y02921D02*
Y02937D01*
X0093Y02298D02*
X00945D01*
X0093Y0227D02*
X00945D01*
X00922Y0176D02*
X00937D01*
X00922Y01733D02*
X00937D01*
X00926Y01238D02*
X00941D01*
X00926Y0121D02*
X00941D01*
G54D15*
X06127Y03741D02*
D01*
X06127Y03741*
X06127Y03742*
X06127Y03742*
X06127Y03743*
X06127Y03743*
X06127Y03744*
X06126Y03744*
X06126Y03745*
X06126Y03745*
X06125Y03746*
X06125Y03746*
X06125Y03746*
X06124Y03747*
X06124Y03747*
X06123Y03747*
X06123Y03748*
X06122Y03748*
X06122Y03748*
X06121Y03748*
X06121Y03748*
X0612Y03748*
X0612Y03748*
X06119*
X06119Y03748*
X06118Y03748*
X06117Y03748*
X06117Y03748*
X06116Y03748*
X06116Y03748*
X06115Y03747*
X06115Y03747*
X06115Y03747*
X06114Y03746*
X06114Y03746*
X06113Y03746*
X06113Y03745*
X06113Y03745*
X06112Y03744*
X06112Y03744*
X06112Y03743*
X06112Y03743*
X06112Y03742*
X06112Y03742*
X06111Y03741*
X06111Y03741*
X06111Y0374*
X06112Y0374*
X06112Y03739*
X06112Y03738*
X06112Y03738*
X06112Y03737*
X06112Y03737*
X06113Y03736*
X06113Y03736*
X06113Y03736*
X06114Y03735*
X06114Y03735*
X06115Y03734*
X06115Y03734*
X06115Y03734*
X06116Y03734*
X06116Y03733*
X06117Y03733*
X06117Y03733*
X06118Y03733*
X06119Y03733*
X06119Y03733*
X0612*
X0612Y03733*
X06121Y03733*
X06121Y03733*
X06122Y03733*
X06122Y03733*
X06123Y03734*
X06123Y03734*
X06124Y03734*
X06124Y03734*
X06125Y03735*
X06125Y03735*
X06125Y03736*
X06126Y03736*
X06126Y03736*
X06126Y03737*
X06127Y03737*
X06127Y03738*
X06127Y03738*
X06127Y03739*
X06127Y0374*
X06127Y0374*
X06127Y03741*
G54D16*
X03441Y02088D02*
D01*
X03441Y02088*
X03441Y02089*
X03441Y02089*
X03441Y0209*
X03441Y02091*
X0344Y02091*
X0344Y02092*
X0344Y02092*
X0344Y02092*
X03439Y02093*
X03439Y02093*
X03439Y02094*
X03438Y02094*
X03438Y02094*
X03437Y02095*
X03437Y02095*
X03436Y02095*
X03436Y02095*
X03435Y02095*
X03435Y02096*
X03434Y02096*
X03434Y02096*
X03433*
X03432Y02096*
X03432Y02096*
X03431Y02095*
X03431Y02095*
X0343Y02095*
X0343Y02095*
X03429Y02095*
X03429Y02094*
X03428Y02094*
X03428Y02094*
X03428Y02093*
X03427Y02093*
X03427Y02092*
X03427Y02092*
X03426Y02092*
X03426Y02091*
X03426Y02091*
X03426Y0209*
X03426Y02089*
X03425Y02089*
X03425Y02088*
X03425Y02088*
X03425Y02087*
X03425Y02087*
X03426Y02086*
X03426Y02086*
X03426Y02085*
X03426Y02085*
X03426Y02084*
X03427Y02084*
X03427Y02083*
X03427Y02083*
X03428Y02082*
X03428Y02082*
X03428Y02082*
X03429Y02081*
X03429Y02081*
X0343Y02081*
X0343Y02081*
X03431Y0208*
X03431Y0208*
X03432Y0208*
X03432Y0208*
X03433Y0208*
X03434*
X03434Y0208*
X03435Y0208*
X03435Y0208*
X03436Y0208*
X03436Y02081*
X03437Y02081*
X03437Y02081*
X03438Y02081*
X03438Y02082*
X03439Y02082*
X03439Y02082*
X03439Y02083*
X0344Y02083*
X0344Y02084*
X0344Y02084*
X0344Y02085*
X03441Y02085*
X03441Y02086*
X03441Y02086*
X03441Y02087*
X03441Y02087*
X03441Y02088*
X02219Y023D02*
D01*
X02219Y02301*
X02219Y02301*
X02219Y02302*
X02219Y02302*
X02219Y02303*
X02219Y02303*
X02218Y02304*
X02218Y02304*
X02218Y02305*
X02218Y02305*
X02217Y02306*
X02217Y02306*
X02216Y02306*
X02216Y02307*
X02215Y02307*
X02215Y02307*
X02214Y02307*
X02214Y02308*
X02213Y02308*
X02213Y02308*
X02212Y02308*
X02212Y02308*
X02211*
X02211Y02308*
X0221Y02308*
X0221Y02308*
X02209Y02308*
X02209Y02307*
X02208Y02307*
X02208Y02307*
X02207Y02307*
X02207Y02306*
X02206Y02306*
X02206Y02306*
X02205Y02305*
X02205Y02305*
X02205Y02304*
X02205Y02304*
X02204Y02303*
X02204Y02303*
X02204Y02302*
X02204Y02302*
X02204Y02301*
X02204Y02301*
X02204Y023*
X02204Y02299*
X02204Y02299*
X02204Y02298*
X02204Y02298*
X02204Y02297*
X02204Y02297*
X02205Y02296*
X02205Y02296*
X02205Y02295*
X02205Y02295*
X02206Y02295*
X02206Y02294*
X02207Y02294*
X02207Y02293*
X02208Y02293*
X02208Y02293*
X02209Y02293*
X02209Y02293*
X0221Y02292*
X0221Y02292*
X02211Y02292*
X02211Y02292*
X02212*
X02212Y02292*
X02213Y02292*
X02213Y02292*
X02214Y02293*
X02214Y02293*
X02215Y02293*
X02215Y02293*
X02216Y02293*
X02216Y02294*
X02217Y02294*
X02217Y02295*
X02218Y02295*
X02218Y02295*
X02218Y02296*
X02218Y02296*
X02219Y02297*
X02219Y02297*
X02219Y02298*
X02219Y02298*
X02219Y02299*
X02219Y02299*
X02219Y023*
X01842Y01318D02*
D01*
X01842Y01319*
X01842Y01319*
X01842Y0132*
X01842Y0132*
X01842Y01321*
X01842Y01321*
X01841Y01322*
X01841Y01322*
X01841Y01323*
X0184Y01323*
X0184Y01324*
X0184Y01324*
X01839Y01324*
X01839Y01325*
X01838Y01325*
X01838Y01325*
X01837Y01325*
X01837Y01326*
X01836Y01326*
X01836Y01326*
X01835Y01326*
X01835Y01326*
X01834*
X01834Y01326*
X01833Y01326*
X01832Y01326*
X01832Y01326*
X01831Y01325*
X01831Y01325*
X0183Y01325*
X0183Y01325*
X01829Y01324*
X01829Y01324*
X01829Y01324*
X01828Y01323*
X01828Y01323*
X01828Y01322*
X01827Y01322*
X01827Y01321*
X01827Y01321*
X01827Y0132*
X01827Y0132*
X01827Y01319*
X01826Y01319*
X01826Y01318*
X01826Y01318*
X01827Y01317*
X01827Y01317*
X01827Y01316*
X01827Y01315*
X01827Y01315*
X01827Y01314*
X01828Y01314*
X01828Y01314*
X01828Y01313*
X01829Y01313*
X01829Y01312*
X01829Y01312*
X0183Y01312*
X0183Y01311*
X01831Y01311*
X01831Y01311*
X01832Y01311*
X01832Y01311*
X01833Y0131*
X01834Y0131*
X01834Y0131*
X01835*
X01835Y0131*
X01836Y0131*
X01836Y01311*
X01837Y01311*
X01837Y01311*
X01838Y01311*
X01838Y01311*
X01839Y01312*
X01839Y01312*
X0184Y01312*
X0184Y01313*
X0184Y01313*
X01841Y01314*
X01841Y01314*
X01841Y01314*
X01842Y01315*
X01842Y01315*
X01842Y01316*
X01842Y01317*
X01842Y01317*
X01842Y01318*
X01842Y01318*
X02989Y01096D02*
D01*
X02989Y01097*
X02989Y01097*
X02989Y01098*
X02989Y01098*
X02989Y01099*
X02988Y01099*
X02988Y011*
X02988Y011*
X02988Y01101*
X02987Y01101*
X02987Y01102*
X02986Y01102*
X02986Y01102*
X02986Y01103*
X02985Y01103*
X02985Y01103*
X02984Y01103*
X02984Y01104*
X02983Y01104*
X02983Y01104*
X02982Y01104*
X02981Y01104*
X02981*
X0298Y01104*
X0298Y01104*
X02979Y01104*
X02979Y01104*
X02978Y01103*
X02978Y01103*
X02977Y01103*
X02977Y01103*
X02976Y01102*
X02976Y01102*
X02976Y01102*
X02975Y01101*
X02975Y01101*
X02975Y011*
X02974Y011*
X02974Y01099*
X02974Y01099*
X02974Y01098*
X02973Y01098*
X02973Y01097*
X02973Y01097*
X02973Y01096*
X02973Y01096*
X02973Y01095*
X02973Y01094*
X02974Y01094*
X02974Y01093*
X02974Y01093*
X02974Y01092*
X02975Y01092*
X02975Y01091*
X02975Y01091*
X02976Y01091*
X02976Y0109*
X02976Y0109*
X02977Y0109*
X02977Y01089*
X02978Y01089*
X02978Y01089*
X02979Y01089*
X02979Y01088*
X0298Y01088*
X0298Y01088*
X02981Y01088*
X02981*
X02982Y01088*
X02983Y01088*
X02983Y01088*
X02984Y01089*
X02984Y01089*
X02985Y01089*
X02985Y01089*
X02986Y0109*
X02986Y0109*
X02986Y0109*
X02987Y01091*
X02987Y01091*
X02988Y01091*
X02988Y01092*
X02988Y01092*
X02988Y01093*
X02989Y01093*
X02989Y01094*
X02989Y01094*
X02989Y01095*
X02989Y01096*
X02989Y01096*
G54D17*
X02172Y0416D02*
Y04235D01*
X02492Y0416D02*
Y04235D01*
X03684Y04098D02*
Y04173D01*
X04059Y04098D02*
Y04173D01*
X06684Y03181D02*
Y03281D01*
X06779Y03306D02*
X06889D01*
X06779Y03156D02*
X06889D01*
X07009Y03166D02*
Y03296D01*
X06659Y03156D02*
Y03306D01*
X06674*
X06659Y03156D02*
X06674D01*
X07009D02*
Y03166D01*
X06994Y03156D02*
X07009D01*
Y03296D02*
Y03306D01*
X06994D02*
X07009D01*
X03319Y03706D02*
X03379D01*
X03504Y02777D02*
Y02816D01*
X05396Y03982D02*
Y04224D01*
X05831*
X05396Y03464D02*
Y03982D01*
Y03464D02*
X05831D01*
Y04224*
X06062Y03536D02*
Y03575D01*
X04377Y02786D02*
Y02846D01*
X04301Y02786D02*
Y02846D01*
X04067Y03036D02*
Y03086D01*
X04011Y03036D02*
Y03086D01*
X01993Y04307D02*
X02093D01*
X01993Y04007D02*
Y04307D01*
Y04007D02*
X02093D01*
Y04307*
X05746Y03323D02*
X05806D01*
X05746Y03399D02*
X05806D01*
X06497Y02246D02*
Y02296D01*
X06441Y02246D02*
Y02296D01*
X06547Y01961D02*
Y02011D01*
X06491Y01961D02*
Y02011D01*
X06372Y02116D02*
Y02176D01*
X06296Y02116D02*
Y02176D01*
X06621Y02101D02*
Y02161D01*
X06697Y02101D02*
Y02161D01*
X06215Y02761D02*
Y02821D01*
X06291Y02761D02*
Y02821D01*
X06334Y02761D02*
Y02821D01*
X0641Y02761D02*
Y02821D01*
X06634Y01383D02*
X06694D01*
X06634Y01459D02*
X06694D01*
X06634Y01493D02*
X06694D01*
X06634Y01569D02*
X06694D01*
X06849Y02124D02*
X06899D01*
X06849Y02068D02*
X06899D01*
X06099Y02143D02*
X06149D01*
X06099Y02199D02*
X06149D01*
X04142Y03776D02*
Y03836D01*
X04066Y03776D02*
Y03836D01*
X04222Y03781D02*
Y03831D01*
X04166Y03781D02*
Y03831D01*
X06444Y03033D02*
X06504D01*
X06444Y03109D02*
X06504D01*
X02171Y03651D02*
Y03711D01*
X02247Y03651D02*
Y03711D01*
X02677Y03541D02*
Y03601D01*
X02601Y03541D02*
Y03601D01*
X03664Y00764D02*
X03724D01*
X03664Y00688D02*
X03724D01*
X03655Y03123D02*
Y03183D01*
X03731Y03123D02*
Y03183D01*
X03716Y03273D02*
Y03323D01*
X0366Y03273D02*
Y03323D01*
X04177Y03583D02*
Y03623D01*
X0673Y02116D02*
X06769D01*
X06215Y02156D02*
X06254D01*
X06869Y01796D02*
Y01835D01*
X06754Y01796D02*
Y01835D01*
X06339Y02431D02*
Y0247D01*
X0699Y01911D02*
X07029D01*
X05985Y02366D02*
X06024D01*
X02914Y03706D02*
X02974D01*
X03014D02*
X03074D01*
X03114D02*
X03174D01*
X02127Y02652D02*
X02166D01*
X04139Y03681D02*
Y0372D01*
X00619Y04066D02*
X00658D01*
X0082D02*
X0086D01*
X01022D02*
X01061D01*
X01224D02*
X01263D01*
X04679Y04186D02*
Y04225D01*
X05239Y04186D02*
Y04225D01*
X04679Y04101D02*
Y0414D01*
X05239Y04106D02*
Y04145D01*
X06103Y02461D02*
X06142D01*
X01914Y04102D02*
X01953D01*
X0167Y04245D02*
X0172D01*
X0167Y04301D02*
X0172D01*
X01807Y04238D02*
X01867D01*
X01807Y04314D02*
X01867D01*
X06632Y03271D02*
Y03321D01*
X06576Y03271D02*
Y03321D01*
Y03136D02*
Y03186D01*
X06632Y03136D02*
Y03186D01*
X04214Y03284D02*
X04274D01*
X04214Y03208D02*
X04274D01*
X04102Y02786D02*
Y02846D01*
X04026Y02786D02*
Y02846D01*
X03997Y02786D02*
Y02846D01*
X03921Y02786D02*
Y02846D01*
X04272Y02786D02*
Y02846D01*
X04196Y02786D02*
Y02846D01*
X01407Y04303D02*
X01507D01*
X01407Y04003D02*
Y04303D01*
Y04003D02*
X01507D01*
Y04303*
G54D18*
X06176Y02217D02*
X06388D01*
X06176Y02414D02*
X06333D01*
X066Y02054D02*
X06813D01*
X06656Y01857D02*
X06813D01*
G54D19*
X03274Y03438D02*
X03313D01*
X03274Y03399D02*
Y03438D01*
Y03162D02*
Y03202D01*
X03589Y03162D02*
X03628D01*
Y03202*
Y03326D02*
Y03438D01*
X03508D02*
X03628D01*
X03274Y03162D02*
X03313D01*
X03404Y03029D02*
Y03092D01*
X03458*
X03544D02*
X03564D01*
Y03072D02*
Y03092D01*
Y02852D02*
Y02872D01*
X03544Y02852D02*
X03564D01*
X03404D02*
X03424D01*
X03404D02*
Y02872D01*
X04934Y04251D02*
Y04261D01*
X05114*
Y04251D02*
Y04261D01*
Y04151D02*
Y04161D01*
X04934Y04151D02*
X05114D01*
X04934D02*
Y04161D01*
X05909Y03792D02*
X06019D01*
X05909Y04038D02*
Y04205D01*
X06224Y03792D02*
X06309D01*
X05909D02*
Y03837D01*
X06309Y03792D02*
Y04205D01*
X05909D02*
X06309D01*
X06444Y03529D02*
Y04356D01*
Y03529D02*
X07003D01*
Y03572D02*
Y04356D01*
X04409Y04251D02*
Y04261D01*
X04589*
Y04251D02*
Y04261D01*
Y04151D02*
Y04161D01*
X04409Y04151D02*
X04589D01*
X04409D02*
Y04161D01*
G54D20*
X00379Y00726D02*
Y00806D01*
X00099Y00726D02*
X00379D01*
Y01006D02*
Y01086D01*
X00099D02*
X00379D01*
X00069Y00726D02*
X00099D01*
X00029Y00766D02*
X00069Y00726D01*
Y01086D02*
X00099D01*
X00029Y01046D02*
X00069Y01086D01*
X00379Y02301D02*
Y02381D01*
X00099Y02301D02*
X00379D01*
Y02581D02*
Y02661D01*
X00099D02*
X00379D01*
X00069Y02301D02*
X00099D01*
X00029Y02341D02*
X00069Y02301D01*
Y02661D02*
X00099D01*
X00029Y02621D02*
X00069Y02661D01*
X00379Y01776D02*
Y01856D01*
X00099Y01776D02*
X00379D01*
Y02056D02*
Y02136D01*
X00099D02*
X00379D01*
X00069Y01776D02*
X00099D01*
X00029Y01816D02*
X00069Y01776D01*
Y02136D02*
X00099D01*
X00029Y02096D02*
X00069Y02136D01*
X00379Y01251D02*
Y01331D01*
X00099Y01251D02*
X00379D01*
Y01531D02*
Y01611D01*
X00099D02*
X00379D01*
X00069Y01251D02*
X00099D01*
X00029Y01291D02*
X00069Y01251D01*
Y01611D02*
X00099D01*
X00029Y01571D02*
X00069Y01611D01*
G54D21*
X0155Y00815D02*
Y02587D01*
X03716Y00815D02*
Y02587D01*
X0155Y00815D02*
X03716D01*
X0155Y02587D02*
X03716D01*
G54D22*
X03493Y01282D02*
Y01308D01*
Y01282D02*
X03516D01*
Y0126D02*
Y01282D01*
Y0126D02*
X03626D01*
Y01282*
X0365*
Y01308*
X03493Y02098D02*
Y02124D01*
X03516*
Y02146*
X03626*
Y02124D02*
Y02146D01*
Y02124D02*
X0365D01*
Y02098D02*
Y02124D01*
X02175Y02517D02*
X02201D01*
X02175Y02493D02*
Y02517D01*
X02153Y02493D02*
X02175D01*
X02153Y02383D02*
Y02493D01*
Y02383D02*
X02175D01*
Y02359D02*
Y02383D01*
Y02359D02*
X02201D01*
X02991Y02517D02*
X03018D01*
Y02493D02*
Y02517D01*
Y02493D02*
X03039D01*
Y02383D02*
Y02493D01*
X03018Y02383D02*
X03039D01*
X03018Y02359D02*
Y02383D01*
X02991Y02359D02*
X03018D01*
X01775Y02098D02*
Y02124D01*
X01751D02*
X01775D01*
X01751D02*
Y02146D01*
X01641D02*
X01751D01*
X01641Y02124D02*
Y02146D01*
X01618Y02124D02*
X01641D01*
X01618Y02098D02*
Y02124D01*
X01775Y01282D02*
Y01308D01*
X01751Y01282D02*
X01775D01*
X01751Y0126D02*
Y01282D01*
X01641Y0126D02*
X01751D01*
X01641D02*
Y01282D01*
X01618D02*
X01641D01*
X01618D02*
Y01308D01*
X02175Y01037D02*
X02201D01*
X02175Y01013D02*
Y01037D01*
X02153Y01013D02*
X02175D01*
X02153Y00903D02*
Y01013D01*
Y00903D02*
X02175D01*
Y00879D02*
Y00903D01*
Y00879D02*
X02201D01*
X02991Y01037D02*
X03018D01*
Y01013D02*
Y01037D01*
Y01013D02*
X03039D01*
Y00903D02*
Y01013D01*
X03018Y00903D02*
X03039D01*
X03018Y00879D02*
Y00903D01*
X02991Y00879D02*
X03018D01*
G54D23*
X07003Y03529D02*
Y03572D01*
G54D24*
X02535Y04188D02*
X02525D01*
X0253*
Y04163*
X02525Y04158*
X0252*
X02515Y04163*
X0256Y04158D02*
Y04188D01*
X02545Y04173*
X02565*
X04136Y04266D02*
X04126D01*
X04131*
Y04241*
X04126Y04236*
X04121*
X04116Y04241*
X04146Y04261D02*
X04151Y04266D01*
X04161*
X04166Y04261*
Y04256*
X04161Y04251*
X04156*
X04161*
X04166Y04246*
Y04241*
X04161Y04236*
X04151*
X04146Y04241*
X00536Y01062D02*
Y01082D01*
X00546Y01092*
X00556Y01082*
Y01062*
Y01077*
X00536*
X00566Y01062D02*
Y01092D01*
X00586Y01062*
Y01092*
X00596Y01087D02*
X00601Y01092D01*
X00611*
X00616Y01087*
Y01082*
X00611Y01077*
X00616Y01072*
Y01067*
X00611Y01062*
X00601*
X00596Y01067*
Y01072*
X00601Y01077*
X00596Y01082*
Y01087*
X00601Y01077D02*
X00611D01*
X03463Y03797D02*
X03493D01*
Y03812*
X03488Y03817*
X03468*
X03463Y03812*
Y03797*
X03468Y03827D02*
X03463Y03832D01*
Y03842*
X03468Y03847*
X03473*
X03478Y03842*
X03483Y03847*
X03488*
X03493Y03842*
Y03832*
X03488Y03827*
X03483*
X03478Y03832*
X03473Y03827*
X03468*
X03478Y03832D02*
Y03842D01*
X01541Y04025D02*
X01566D01*
X01571Y0403*
Y0404*
X01566Y04045*
X01541*
X01571Y04055D02*
Y04065D01*
Y0406*
X01541*
X01546Y04055*
X01541Y041D02*
X01546Y0409D01*
X01556Y0408*
X01566*
X01571Y04085*
Y04095*
X01566Y041*
X01561*
X01556Y04095*
Y0408*
X06013Y0226D02*
Y02235D01*
X06018Y0223*
X06028*
X06033Y02235*
Y0226*
X06063Y0223D02*
X06043D01*
X06063Y0225*
Y02255*
X06058Y0226*
X06048*
X06043Y02255*
X06341Y03788D02*
Y03758D01*
X06356*
X06361Y03763*
Y03783*
X06356Y03788*
X06341*
X06371Y03783D02*
X06376Y03788D01*
X06386*
X06391Y03783*
Y03778*
X06386Y03773*
X06381*
X06386*
X06391Y03768*
Y03763*
X06386Y03758*
X06376*
X06371Y03763*
X06951Y03391D02*
X06971Y03361D01*
Y03391D02*
X06951Y03361D01*
X06981D02*
X06991D01*
X06986*
Y03391*
X06981Y03386*
X03159Y0342D02*
Y03395D01*
X03164Y0339*
X03174*
X03179Y03395*
Y0342*
X03189Y0339D02*
X03199D01*
X03194*
Y0342*
X03189Y03415*
X03214Y0339D02*
X03224D01*
X03219*
Y0342*
X03214Y03415*
X03588Y02889D02*
Y02864D01*
X03593Y02859*
X03603*
X03608Y02864*
Y02889*
X03618Y02859D02*
X03628D01*
X03623*
Y02889*
X03618Y02884*
X03643D02*
X03648Y02889D01*
X03658*
X03663Y02884*
Y02879*
X03658Y02874*
X03653*
X03658*
X03663Y02869*
Y02864*
X03658Y02859*
X03648*
X03643Y02864*
X02629Y04251D02*
Y04226D01*
X02634Y04221*
X02644*
X02649Y04226*
Y04251*
X02679D02*
X02659D01*
Y04236*
X02669Y04241*
X02674*
X02679Y04236*
Y04226*
X02674Y04221*
X02664*
X02659Y04226*
X03371Y03519D02*
X03341D01*
Y03534*
X03346Y03539*
X03356*
X03361Y03534*
Y03519*
Y03529D02*
X03371Y03539D01*
Y03569D02*
Y03549D01*
X03351Y03569*
X03346*
X03341Y03564*
Y03554*
X03346Y03549*
X03371Y03579D02*
Y03589D01*
Y03584*
X03341*
X03346Y03579*
X03446Y02694D02*
Y02724D01*
X03461*
X03466Y02719*
Y02709*
X03461Y02704*
X03446*
X03456D02*
X03466Y02694D01*
X03491D02*
Y02724D01*
X03476Y02709*
X03496*
X03526Y02694D02*
X03506D01*
X03526Y02714*
Y02719*
X03521Y02724*
X03511*
X03506Y02719*
X03705Y03604D02*
X03675D01*
Y03619*
X0368Y03624*
X0369*
X03695Y03619*
Y03604*
Y03614D02*
X03705Y03624D01*
Y03654D02*
Y03634D01*
X03685Y03654*
X0368*
X03675Y03649*
Y03639*
X0368Y03634*
X03675Y03684D02*
X0368Y03674D01*
X0369Y03664*
X037*
X03705Y03669*
Y03679*
X037Y03684*
X03695*
X0369Y03679*
Y03664*
X01787Y00253D02*
Y00283D01*
X01802*
X01807Y00278*
Y00268*
X01802Y00263*
X01787*
X01837Y00253D02*
X01817D01*
X01837Y00273*
Y00278*
X01832Y00283*
X01822*
X01817Y00278*
X04951Y04322D02*
X04946Y04327D01*
X04936*
X04931Y04322*
Y04317*
X04936Y04312*
X04946*
X04951Y04307*
Y04302*
X04946Y04297*
X04936*
X04931Y04302*
X04981Y04327D02*
X04971Y04322D01*
X04961Y04312*
Y04302*
X04966Y04297*
X04976*
X04981Y04302*
Y04307*
X04976Y04312*
X04961*
X05652Y02744D02*
Y02719D01*
X05657Y02714*
X05667*
X05672Y02719*
Y02744*
X05682Y02714D02*
X05692D01*
X05687*
Y02744*
X05682Y02739*
X05707D02*
X05712Y02744D01*
X05722*
X05727Y02739*
Y02719*
X05722Y02714*
X05712*
X05707Y02719*
Y02739*
X06368Y03415D02*
Y0339D01*
X06373Y03385*
X06383*
X06388Y0339*
Y03415*
X06398Y0341D02*
X06403Y03415D01*
X06413*
X06418Y0341*
Y03405*
X06413Y034*
X06418Y03395*
Y0339*
X06413Y03385*
X06403*
X06398Y0339*
Y03395*
X06403Y034*
X06398Y03405*
Y0341*
X06403Y034D02*
X06413D01*
X05411Y03411D02*
X05406Y03416D01*
X05396*
X05391Y03411*
Y03406*
X05396Y03401*
X05406*
X05411Y03396*
Y03391*
X05406Y03387*
X05396*
X05391Y03391*
X05421Y03416D02*
Y03387D01*
X05431Y03396*
X05441Y03387*
Y03416*
X05451Y03387D02*
X05461D01*
X05456*
Y03416*
X05451Y03411*
X04144Y02907D02*
Y02887D01*
X04159*
Y02897*
Y02887*
X04174*
X04144Y02917D02*
X04174D01*
Y02932*
X04169Y02937*
X04164*
X04159Y02932*
Y02917*
Y02932*
X04154Y02937*
X04149*
X04144Y02932*
Y02917*
X04149Y02947D02*
X04144Y02952D01*
Y02962*
X04149Y02967*
X04154*
X04159Y02962*
Y02957*
Y02962*
X04164Y02967*
X04169*
X04174Y02962*
Y02952*
X04169Y02947*
X06866Y02939D02*
Y02909D01*
X06886*
X06916D02*
X06896D01*
X06916Y02929*
Y02934*
X06911Y02939*
X06901*
X06896Y02934*
X06141Y03434D02*
X06121D01*
Y03419*
X06131*
X06121*
Y03404*
X06151D02*
X06161D01*
X06156*
Y03434*
X06151Y03429*
X00881Y01101D02*
Y01071D01*
X00896*
X00901Y01076*
Y01096*
X00896Y01101*
X00881*
X00911Y01071D02*
X00921D01*
X00916*
Y01101*
X00911Y01096*
X00936D02*
X00941Y01101D01*
X00951*
X00956Y01096*
Y01091*
X00951Y01086*
X00956Y01081*
Y01076*
X00951Y01071*
X00941*
X00936Y01076*
Y01081*
X00941Y01086*
X00936Y01091*
Y01096*
X00941Y01086D02*
X00951D01*
X01162Y04167D02*
X01192D01*
Y04182*
X01187Y04187*
X01167*
X01162Y04182*
Y04167*
X01192Y04197D02*
Y04207D01*
Y04202*
X01162*
X01167Y04197*
X01192Y04237D02*
X01162D01*
X01177Y04222*
Y04242*
X06351Y04188D02*
X06341D01*
X06346*
Y04163*
X06341Y04158*
X06336*
X06331Y04163*
X06361Y04158D02*
X06371D01*
X06366*
Y04188*
X06361Y04183*
X04338Y02914D02*
X04333Y02909D01*
Y02899*
X04338Y02894*
X04358*
X04363Y02899*
Y02909*
X04358Y02914*
X04333Y02924D02*
Y02944D01*
X04338*
X04358Y02924*
X04363*
Y02974D02*
Y02954D01*
X04343Y02974*
X04338*
X04333Y02969*
Y02959*
X04338Y02954*
X03957Y03208D02*
X03952Y03203D01*
Y03193*
X03957Y03188*
X03977*
X03982Y03193*
Y03203*
X03977Y03208*
X03952Y03218D02*
Y03238D01*
X03957*
X03977Y03218*
X03982*
X03952Y03268D02*
X03957Y03258D01*
X03967Y03248*
X03977*
X03982Y03253*
Y03263*
X03977Y03268*
X03972*
X03967Y03263*
Y03248*
X04011Y03208D02*
X04006Y03203D01*
Y03193*
X04011Y03188*
X04031*
X04036Y03193*
Y03203*
X04031Y03208*
X04006Y03218D02*
Y03238D01*
X04011*
X04031Y03218*
X04036*
X04006Y03248D02*
Y03268D01*
X04011*
X04031Y03248*
X04036*
X00404Y00728D02*
Y00748D01*
X00414Y00758*
X00424Y00748*
Y00728*
Y00743*
X00404*
X00434Y00728D02*
Y00758D01*
X00454Y00728*
Y00758*
X00479Y00728D02*
Y00758D01*
X00464Y00743*
X00484*
X01556Y02619D02*
Y02649D01*
X01571*
X01576Y02644*
Y02634*
X01571Y02629*
X01556*
X01586Y02619D02*
X01596D01*
X01591*
Y02649*
X01586Y02644*
X01953Y04005D02*
Y03995D01*
Y04*
X01978*
X01983Y03995*
Y0399*
X01978Y03985*
X01983Y04015D02*
X01953D01*
Y0403*
X01958Y04035*
X01968*
X01973Y0403*
Y04015*
X01983Y04065D02*
Y04045D01*
X01963Y04065*
X01958*
X01953Y0406*
Y0405*
X01958Y04045*
X06951Y03499D02*
X06941D01*
X06946*
Y03474*
X06941Y03469*
X06936*
X06931Y03474*
X06981Y03469D02*
X06961D01*
X06981Y03489*
Y03494*
X06976Y03499*
X06966*
X06961Y03494*
X00406Y02301D02*
Y02321D01*
X00416Y02331*
X00426Y02321*
Y02301*
Y02316*
X00406*
X00436Y02301D02*
Y02331D01*
X00456Y02301*
Y02331*
X00466Y02301D02*
X00476D01*
X00471*
Y02331*
X00466Y02326*
X00404Y01775D02*
Y01795D01*
X00414Y01805*
X00424Y01795*
Y01775*
Y0179*
X00404*
X00434Y01775D02*
Y01805D01*
X00454Y01775*
Y01805*
X00484Y01775D02*
X00464D01*
X00484Y01795*
Y018*
X00479Y01805*
X00469*
X00464Y018*
X00406Y01252D02*
Y01272D01*
X00416Y01282*
X00426Y01272*
Y01252*
Y01267*
X00406*
X00436Y01252D02*
Y01282D01*
X00456Y01252*
Y01282*
X00466Y01277D02*
X00471Y01282D01*
X00481*
X00486Y01277*
Y01272*
X00481Y01267*
X00476*
X00481*
X00486Y01262*
Y01257*
X00481Y01252*
X00471*
X00466Y01257*
X00536Y02112D02*
Y02132D01*
X00546Y02142*
X00556Y02132*
Y02112*
Y02127*
X00536*
X00566Y02112D02*
Y02142D01*
X00586Y02112*
Y02142*
X00616D02*
X00596D01*
Y02127*
X00606Y02132*
X00611*
X00616Y02127*
Y02117*
X00611Y02112*
X00601*
X00596Y02117*
X00536Y02637D02*
Y02657D01*
X00546Y02667*
X00556Y02657*
Y02637*
Y02652*
X00536*
X00566Y02637D02*
Y02667D01*
X00586Y02637*
Y02667*
X00616D02*
X00606Y02662D01*
X00596Y02652*
Y02642*
X00601Y02637*
X00611*
X00616Y02642*
Y02647*
X00611Y02652*
X00596*
X00536Y01587D02*
Y01607D01*
X00546Y01617*
X00556Y01607*
Y01587*
Y01602*
X00536*
X00566Y01587D02*
Y01617D01*
X00586Y01587*
Y01617*
X00596D02*
X00616D01*
Y01612*
X00596Y01592*
Y01587*
X05764Y0327D02*
X05759Y03275D01*
X05749*
X05744Y0327*
Y0325*
X05749Y03245*
X05759*
X05764Y0325*
X05774Y03245D02*
X05784D01*
X05779*
Y03275*
X05774Y0327*
X05622Y03266D02*
X05617Y03271D01*
X05607*
X05602Y03266*
Y03246*
X05607Y03241*
X05617*
X05622Y03246*
X05652Y03241D02*
X05632D01*
X05652Y03261*
Y03266*
X05647Y03271*
X05637*
X05632Y03266*
X06461Y02166D02*
X06456Y02161D01*
Y02151*
X06461Y02146*
X06481*
X06486Y02151*
Y02161*
X06481Y02166*
X06461Y02176D02*
X06456Y02181D01*
Y02191*
X06461Y02196*
X06466*
X06471Y02191*
Y02186*
Y02191*
X06476Y02196*
X06481*
X06486Y02191*
Y02181*
X06481Y02176*
X06505Y02085D02*
X065Y0208D01*
Y0207*
X06505Y02065*
X06525*
X0653Y0207*
Y0208*
X06525Y02085*
X0653Y0211D02*
X065D01*
X06515Y02095*
Y02115*
X06326Y02057D02*
X06321Y02062D01*
X06311*
X06306Y02057*
Y02037*
X06311Y02032*
X06321*
X06326Y02037*
X06356Y02062D02*
X06336D01*
Y02047*
X06346Y02052*
X06351*
X06356Y02047*
Y02037*
X06351Y02032*
X06341*
X06336Y02037*
X0665Y02231D02*
X06645Y02226D01*
Y02216*
X0665Y02211*
X0667*
X06675Y02216*
Y02226*
X0667Y02231*
X06645Y02261D02*
X0665Y02251D01*
X0666Y02241*
X0667*
X06675Y02246*
Y02256*
X0667Y02261*
X06665*
X0666Y02256*
Y02241*
X06179Y02903D02*
X06174Y02898D01*
Y02888*
X06179Y02883*
X06199*
X06204Y02888*
Y02898*
X06199Y02903*
X06174Y02913D02*
Y02933D01*
X06179*
X06199Y02913*
X06204*
X06312Y029D02*
X06307Y02895D01*
Y02885*
X06312Y0288*
X06332*
X06337Y02885*
Y02895*
X06332Y029*
X06312Y0291D02*
X06307Y02915D01*
Y02925*
X06312Y0293*
X06317*
X06322Y02925*
X06327Y0293*
X06332*
X06337Y02925*
Y02915*
X06332Y0291*
X06327*
X06322Y02915*
X06317Y0291*
X06312*
X06322Y02915D02*
Y02925D01*
X06199Y02702D02*
X06194Y02707D01*
X06184*
X06179Y02702*
Y02682*
X06184Y02677*
X06194*
X06199Y02682*
X06209D02*
X06214Y02677D01*
X06224*
X06229Y02682*
Y02702*
X06224Y02707*
X06214*
X06209Y02702*
Y02697*
X06214Y02692*
X06229*
X06197Y02552D02*
X06192Y02557D01*
X06182*
X06177Y02552*
Y02532*
X06182Y02527*
X06192*
X06197Y02532*
X06207Y02527D02*
X06217D01*
X06212*
Y02557*
X06207Y02552*
X06232D02*
X06237Y02557D01*
X06247*
X06252Y02552*
Y02532*
X06247Y02527*
X06237*
X06232Y02532*
Y02552*
X06198Y02601D02*
X06193Y02606D01*
X06183*
X06178Y02601*
Y02581*
X06183Y02576*
X06193*
X06198Y02581*
X06208Y02576D02*
X06218D01*
X06213*
Y02606*
X06208Y02601*
X06233Y02576D02*
X06243D01*
X06238*
Y02606*
X06233Y02601*
X06199Y0265D02*
X06194Y02655D01*
X06184*
X06179Y0265*
Y0263*
X06184Y02625*
X06194*
X06199Y0263*
X06209Y02625D02*
X06219D01*
X06214*
Y02655*
X06209Y0265*
X06254Y02625D02*
X06234D01*
X06254Y02645*
Y0265*
X06249Y02655*
X06239*
X06234Y0265*
X06761Y01422D02*
X06756Y01427D01*
X06746*
X06741Y01422*
Y01402*
X06746Y01397*
X06756*
X06761Y01402*
X06771Y01397D02*
X06781D01*
X06776*
Y01427*
X06771Y01422*
X06796D02*
X06801Y01427D01*
X06811*
X06816Y01422*
Y01417*
X06811Y01412*
X06806*
X06811*
X06816Y01407*
Y01402*
X06811Y01397*
X06801*
X06796Y01402*
X06762Y01496D02*
X06757Y01501D01*
X06747*
X06742Y01496*
Y01476*
X06747Y01471*
X06757*
X06762Y01476*
X06772Y01471D02*
X06782D01*
X06777*
Y01501*
X06772Y01496*
X06812Y01471D02*
Y01501D01*
X06797Y01486*
X06817*
X06761Y01562D02*
X06756Y01567D01*
X06746*
X06741Y01562*
Y01542*
X06746Y01537*
X06756*
X06761Y01542*
X06771Y01537D02*
X06781D01*
X06776*
Y01567*
X06771Y01562*
X06816Y01567D02*
X06796D01*
Y01552*
X06806Y01557*
X06811*
X06816Y01552*
Y01542*
X06811Y01537*
X06801*
X06796Y01542*
X06727Y01628D02*
X06722Y01633D01*
X06712*
X06707Y01628*
Y01608*
X06712Y01603*
X06722*
X06727Y01608*
X06737Y01603D02*
X06747D01*
X06742*
Y01633*
X06737Y01628*
X06782Y01633D02*
X06772Y01628D01*
X06762Y01618*
Y01608*
X06767Y01603*
X06777*
X06782Y01608*
Y01613*
X06777Y01618*
X06762*
X06728Y01693D02*
X06723Y01698D01*
X06713*
X06708Y01693*
Y01673*
X06713Y01668*
X06723*
X06728Y01673*
X06738Y01668D02*
X06748D01*
X06743*
Y01698*
X06738Y01693*
X06763Y01698D02*
X06783D01*
Y01693*
X06763Y01673*
Y01668*
X06727Y01758D02*
X06722Y01763D01*
X06712*
X06707Y01758*
Y01738*
X06712Y01733*
X06722*
X06727Y01738*
X06737Y01733D02*
X06747D01*
X06742*
Y01763*
X06737Y01758*
X06762D02*
X06767Y01763D01*
X06777*
X06782Y01758*
Y01753*
X06777Y01748*
X06782Y01743*
Y01738*
X06777Y01733*
X06767*
X06762Y01738*
Y01743*
X06767Y01748*
X06762Y01753*
Y01758*
X06767Y01748D02*
X06777D01*
X06853Y02169D02*
X06848Y02174D01*
X06838*
X06833Y02169*
Y02149*
X06838Y02144*
X06848*
X06853Y02149*
X06863Y02144D02*
X06873D01*
X06868*
Y02174*
X06863Y02169*
X06888Y02149D02*
X06893Y02144D01*
X06903*
X06908Y02149*
Y02169*
X06903Y02174*
X06893*
X06888Y02169*
Y02164*
X06893Y02159*
X06908*
X06924Y01978D02*
X06919Y01973D01*
Y01963*
X06924Y01958*
X06944*
X06949Y01963*
Y01973*
X06944Y01978*
X06949Y02008D02*
Y01988D01*
X06929Y02008*
X06924*
X06919Y02003*
Y01993*
X06924Y01988*
Y02018D02*
X06919Y02023D01*
Y02033*
X06924Y02038*
X06944*
X06949Y02033*
Y02023*
X06944Y02018*
X06924*
X06101Y02113D02*
X06096Y02118D01*
X06086*
X06081Y02113*
Y02093*
X06086Y02088*
X06096*
X06101Y02093*
X06131Y02088D02*
X06111D01*
X06131Y02108*
Y02113*
X06126Y02118*
X06116*
X06111Y02113*
X06141Y02088D02*
X06151D01*
X06146*
Y02118*
X06141Y02113*
X06051Y02439D02*
X06046Y02434D01*
Y02424*
X06051Y02419*
X06071*
X06076Y02424*
Y02434*
X06071Y02439*
X06076Y02469D02*
Y02449D01*
X06056Y02469*
X06051*
X06046Y02464*
Y02454*
X06051Y02449*
X06076Y02499D02*
Y02479D01*
X06056Y02499*
X06051*
X06046Y02494*
Y02484*
X06051Y02479*
X04132Y03908D02*
X04127Y03903D01*
Y03893*
X04132Y03888*
X04152*
X04157Y03893*
Y03903*
X04152Y03908*
X04127Y03938D02*
Y03918D01*
X04142*
X04137Y03928*
Y03933*
X04142Y03938*
X04152*
X04157Y03933*
Y03923*
X04152Y03918*
X04157Y03963D02*
X04127D01*
X04142Y03948*
Y03968*
X04273Y03825D02*
X04268Y0382D01*
Y0381*
X04273Y03805*
X04293*
X04298Y0381*
Y0382*
X04293Y03825*
X04268Y03855D02*
Y03835D01*
X04283*
X04278Y03845*
Y0385*
X04283Y03855*
X04293*
X04298Y0385*
Y0384*
X04293Y03835*
X04268Y03885D02*
Y03865D01*
X04283*
X04278Y03875*
Y0388*
X04283Y03885*
X04293*
X04298Y0388*
Y0387*
X04293Y03865*
X06289Y03068D02*
X06284Y03073D01*
X06274*
X06269Y03068*
Y03048*
X06274Y03043*
X06284*
X06289Y03048*
X06319Y03073D02*
X06299D01*
Y03058*
X06309Y03063*
X06314*
X06319Y03058*
Y03048*
X06314Y03043*
X06304*
X06299Y03048*
X06349Y03073D02*
X06339Y03068D01*
X06329Y03058*
Y03048*
X06334Y03043*
X06344*
X06349Y03048*
Y03053*
X06344Y03058*
X06329*
X06594Y02982D02*
X06589Y02987D01*
X06579*
X06574Y02982*
Y02962*
X06579Y02957*
X06589*
X06594Y02962*
X06624Y02987D02*
X06604D01*
Y02972*
X06614Y02977*
X06619*
X06624Y02972*
Y02962*
X06619Y02957*
X06609*
X06604Y02962*
X06634Y02987D02*
X06654D01*
Y02982*
X06634Y02962*
Y02957*
X02207Y03783D02*
X02202Y03778D01*
Y03768*
X02207Y03763*
X02227*
X02232Y03768*
Y03778*
X02227Y03783*
X02202Y03813D02*
Y03793D01*
X02217*
X02212Y03803*
Y03808*
X02217Y03813*
X02227*
X02232Y03808*
Y03798*
X02227Y03793*
X02207Y03823D02*
X02202Y03828D01*
Y03838*
X02207Y03843*
X02212*
X02217Y03838*
X02222Y03843*
X02227*
X02232Y03838*
Y03828*
X02227Y03823*
X02222*
X02217Y03828*
X02212Y03823*
X02207*
X02217Y03828D02*
Y03838D01*
X02071Y03636D02*
X02066Y03631D01*
Y03621*
X02071Y03616*
X02091*
X02096Y03621*
Y03631*
X02091Y03636*
X02066Y03666D02*
Y03646D01*
X02081*
X02076Y03656*
Y03661*
X02081Y03666*
X02091*
X02096Y03661*
Y03651*
X02091Y03646*
Y03676D02*
X02096Y03681D01*
Y03691*
X02091Y03696*
X02071*
X02066Y03691*
Y03681*
X02071Y03676*
X02076*
X02081Y03681*
Y03696*
X02697Y03374D02*
X02692Y03369D01*
Y03359*
X02697Y03354*
X02717*
X02722Y03359*
Y03369*
X02717Y03374*
X02692Y03404D02*
X02697Y03394D01*
X02707Y03384*
X02717*
X02722Y03389*
Y03399*
X02717Y03404*
X02712*
X02707Y03399*
Y03384*
X02697Y03414D02*
X02692Y03419D01*
Y03429*
X02697Y03434*
X02717*
X02722Y03429*
Y03419*
X02717Y03414*
X02697*
X02772Y03462D02*
X02767Y03457D01*
Y03447*
X02772Y03442*
X02792*
X02797Y03447*
Y03457*
X02792Y03462*
X02767Y03492D02*
X02772Y03482D01*
X02782Y03472*
X02792*
X02797Y03477*
Y03487*
X02792Y03492*
X02787*
X02782Y03487*
Y03472*
X02797Y03502D02*
Y03512D01*
Y03507*
X02767*
X02772Y03502*
X03514Y00733D02*
X03509Y00738D01*
X03499*
X03494Y00733*
Y00713*
X03499Y00708*
X03509*
X03514Y00713*
X03544Y00738D02*
X03534Y00733D01*
X03524Y00723*
Y00713*
X03529Y00708*
X03539*
X03544Y00713*
Y00718*
X03539Y00723*
X03524*
X03574Y00708D02*
X03554D01*
X03574Y00728*
Y00733*
X03569Y00738*
X03559*
X03554Y00733*
X0378Y00638D02*
X03775Y00643D01*
X03765*
X0376Y00638*
Y00618*
X03765Y00613*
X03775*
X0378Y00618*
X0381Y00643D02*
X038Y00638D01*
X0379Y00628*
Y00618*
X03795Y00613*
X03805*
X0381Y00618*
Y00623*
X03805Y00628*
X0379*
X0382Y00638D02*
X03825Y00643D01*
X03835*
X0384Y00638*
Y00633*
X03835Y00628*
X0383*
X03835*
X0384Y00623*
Y00618*
X03835Y00613*
X03825*
X0382Y00618*
X03772Y03129D02*
X03767Y03134D01*
X03757*
X03752Y03129*
Y03109*
X03757Y03104*
X03767*
X03772Y03109*
X03802Y03134D02*
X03792Y03129D01*
X03782Y03119*
Y03109*
X03787Y03104*
X03797*
X03802Y03109*
Y03114*
X03797Y03119*
X03782*
X03832Y03134D02*
X03812D01*
Y03119*
X03822Y03124*
X03827*
X03832Y03119*
Y03109*
X03827Y03104*
X03817*
X03812Y03109*
X03806Y0331D02*
X03801Y03315D01*
X03791*
X03786Y0331*
Y0329*
X03791Y03285*
X03801*
X03806Y0329*
X03836Y03315D02*
X03826Y0331D01*
X03816Y033*
Y0329*
X03821Y03285*
X03831*
X03836Y0329*
Y03295*
X03831Y033*
X03816*
X03866Y03315D02*
X03856Y0331D01*
X03846Y033*
Y0329*
X03851Y03285*
X03861*
X03866Y0329*
Y03295*
X03861Y033*
X03846*
X03685Y03415D02*
X0368Y0342D01*
X0367*
X03665Y03415*
Y03395*
X0367Y0339*
X0368*
X03685Y03395*
X03715Y0342D02*
X03705Y03415D01*
X03695Y03405*
Y03395*
X037Y0339*
X0371*
X03715Y03395*
Y034*
X0371Y03405*
X03695*
X03725Y0342D02*
X03745D01*
Y03415*
X03725Y03395*
Y0339*
X06069Y03689D02*
Y03659D01*
X06084*
X06089Y03664*
Y03684*
X06084Y03689*
X06069*
X06099Y03659D02*
X06109D01*
X06104*
Y03689*
X06099Y03684*
X06206Y0348D02*
Y0345D01*
X06221*
X06226Y03455*
Y03475*
X06221Y0348*
X06206*
X06256Y0345D02*
X06236D01*
X06256Y0347*
Y03475*
X06251Y0348*
X06241*
X06236Y03475*
X04324Y03663D02*
Y03633D01*
X04339*
X04344Y03638*
Y03658*
X04339Y03663*
X04324*
X04369Y03633D02*
Y03663D01*
X04354Y03648*
X04374*
X02865Y03548D02*
X02895D01*
Y03563*
X0289Y03568*
X0287*
X02865Y03563*
Y03548*
Y03598D02*
Y03578D01*
X0288*
X02875Y03588*
Y03593*
X0288Y03598*
X0289*
X02895Y03593*
Y03583*
X0289Y03578*
X02705Y03852D02*
Y03822D01*
X0272*
X02725Y03827*
Y03847*
X0272Y03852*
X02705*
X02755D02*
X02745Y03847D01*
X02735Y03837*
Y03827*
X0274Y03822*
X0275*
X02755Y03827*
Y03832*
X0275Y03837*
X02735*
X03235Y035D02*
X03265D01*
Y03515*
X0326Y0352*
X0324*
X03235Y03515*
Y035*
Y0353D02*
Y0355D01*
X0324*
X0326Y0353*
X03265*
X0359Y03961D02*
X0362D01*
Y03976*
X03615Y03981*
X03595*
X0359Y03976*
Y03961*
X03615Y03991D02*
X0362Y03996D01*
Y04006*
X03615Y04011*
X03595*
X0359Y04006*
Y03996*
X03595Y03991*
X036*
X03605Y03996*
Y04011*
X03578Y03571D02*
X03608D01*
Y03586*
X03603Y03591*
X03583*
X03578Y03586*
Y03571*
X03608Y03601D02*
Y03611D01*
Y03606*
X03578*
X03583Y03601*
Y03626D02*
X03578Y03631D01*
Y03641*
X03583Y03646*
X03603*
X03608Y03641*
Y03631*
X03603Y03626*
X03583*
X00561Y04178D02*
X00591D01*
Y04193*
X00586Y04198*
X00566*
X00561Y04193*
Y04178*
X00591Y04208D02*
Y04218D01*
Y04213*
X00561*
X00566Y04208*
X00591Y04233D02*
Y04243D01*
Y04238*
X00561*
X00566Y04233*
X00764Y04168D02*
X00794D01*
Y04183*
X00789Y04188*
X00769*
X00764Y04183*
Y04168*
X00794Y04198D02*
Y04208D01*
Y04203*
X00764*
X00769Y04198*
X00794Y04243D02*
Y04223D01*
X00774Y04243*
X00769*
X00764Y04238*
Y04228*
X00769Y04223*
X0096Y04164D02*
X0099D01*
Y04179*
X00985Y04184*
X00965*
X0096Y04179*
Y04164*
X0099Y04194D02*
Y04204D01*
Y04199*
X0096*
X00965Y04194*
Y04219D02*
X0096Y04224D01*
Y04234*
X00965Y04239*
X0097*
X00975Y04234*
Y04229*
Y04234*
X0098Y04239*
X00985*
X0099Y04234*
Y04224*
X00985Y04219*
X00881Y02151D02*
Y02121D01*
X00896*
X00901Y02126*
Y02146*
X00896Y02151*
X00881*
X00911Y02121D02*
X00921D01*
X00916*
Y02151*
X00911Y02146*
X00956Y02151D02*
X00936D01*
Y02136*
X00946Y02141*
X00951*
X00956Y02136*
Y02126*
X00951Y02121*
X00941*
X00936Y02126*
X00881Y02676D02*
Y02646D01*
X00896*
X00901Y02651*
Y02671*
X00896Y02676*
X00881*
X00911Y02646D02*
X00921D01*
X00916*
Y02676*
X00911Y02671*
X00956Y02676D02*
X00946Y02671D01*
X00936Y02661*
Y02651*
X00941Y02646*
X00951*
X00956Y02651*
Y02656*
X00951Y02661*
X00936*
X00881Y01626D02*
Y01596D01*
X00896*
X00901Y01601*
Y01621*
X00896Y01626*
X00881*
X00911Y01596D02*
X00921D01*
X00916*
Y01626*
X00911Y01621*
X00936Y01626D02*
X00956D01*
Y01621*
X00936Y01601*
Y01596*
X04496Y02854D02*
Y02834D01*
X04511*
Y02844*
Y02834*
X04526*
X04496Y02864D02*
X04526D01*
Y02879*
X04521Y02884*
X04516*
X04511Y02879*
Y02864*
Y02879*
X04506Y02884*
X04501*
X04496Y02879*
Y02864*
X04526Y02914D02*
Y02894D01*
X04506Y02914*
X04501*
X04496Y02909*
Y02899*
X04501Y02894*
X05973Y01899D02*
Y01869D01*
X05993*
X06003D02*
X06013D01*
X06008*
Y01899*
X06003Y01894*
X04137Y0366D02*
Y0369D01*
X04152*
X04157Y03685*
Y03675*
X04152Y0367*
X04137*
X04147D02*
X04157Y0366D01*
X04167D02*
X04177D01*
X04172*
Y0369*
X04167Y03685*
X06766Y02174D02*
X06736D01*
Y02189*
X06741Y02194*
X06751*
X06756Y02189*
Y02174*
Y02184D02*
X06766Y02194D01*
Y02224D02*
Y02204D01*
X06746Y02224*
X06741*
X06736Y02219*
Y02209*
X06741Y02204*
X06209Y02058D02*
Y02088D01*
X06224*
X06229Y02083*
Y02073*
X06224Y02068*
X06209*
X06219D02*
X06229Y02058D01*
X06239Y02083D02*
X06244Y02088D01*
X06254*
X06259Y02083*
Y02078*
X06254Y02073*
X06249*
X06254*
X06259Y02068*
Y02063*
X06254Y02058*
X06244*
X06239Y02063*
X06845Y0175D02*
Y01779D01*
X0686*
X06865Y01774*
Y01764*
X0686Y0176*
X06845*
X06855D02*
X06865Y0175D01*
X0689D02*
Y01779D01*
X06875Y01764*
X06895*
X06621Y01807D02*
Y01837D01*
X06636*
X06641Y01832*
Y01822*
X06636Y01817*
X06621*
X06631D02*
X06641Y01807D01*
X06671Y01837D02*
X06661Y01832D01*
X06651Y01822*
Y01812*
X06656Y01807*
X06666*
X06671Y01812*
Y01817*
X06666Y01822*
X06651*
X06183Y0244D02*
Y0247D01*
X06198*
X06203Y02465*
Y02455*
X06198Y0245*
X06183*
X06193D02*
X06203Y0244D01*
X06213Y0247D02*
X06233D01*
Y02465*
X06213Y02445*
Y0244*
X07027Y01965D02*
X06997D01*
Y0198*
X07002Y01985*
X07012*
X07017Y0198*
Y01965*
Y01975D02*
X07027Y01985D01*
X07002Y01995D02*
X06997Y02D01*
Y0201*
X07002Y02015*
X07007*
X07012Y0201*
X07017Y02015*
X07022*
X07027Y0201*
Y02*
X07022Y01995*
X07017*
X07012Y02*
X07007Y01995*
X07002*
X07012Y02D02*
Y0201D01*
X06016Y02461D02*
X05986D01*
Y02476*
X05991Y02481*
X06001*
X06006Y02476*
Y02461*
Y02471D02*
X06016Y02481D01*
X06011Y02491D02*
X06016Y02496D01*
Y02506*
X06011Y02511*
X05991*
X05986Y02506*
Y02496*
X05991Y02491*
X05996*
X06001Y02496*
Y02511*
X02972Y03513D02*
X02942D01*
Y03528*
X02947Y03533*
X02957*
X02962Y03528*
Y03513*
Y03523D02*
X02972Y03533D01*
Y03543D02*
Y03553D01*
Y03548*
X02942*
X02947Y03543*
Y03568D02*
X02942Y03573D01*
Y03583*
X02947Y03588*
X02952*
X02957Y03583*
X02962Y03588*
X02967*
X02972Y03583*
Y03573*
X02967Y03568*
X02962*
X02957Y03573*
X02952Y03568*
X02947*
X02957Y03573D02*
Y03583D01*
X03066Y03513D02*
X03036D01*
Y03528*
X03041Y03533*
X03051*
X03056Y03528*
Y03513*
Y03523D02*
X03066Y03533D01*
Y03543D02*
Y03553D01*
Y03548*
X03036*
X03041Y03543*
X03061Y03568D02*
X03066Y03573D01*
Y03583*
X03061Y03588*
X03041*
X03036Y03583*
Y03573*
X03041Y03568*
X03046*
X03051Y03573*
Y03588*
X03168Y0351D02*
X03138D01*
Y03525*
X03143Y0353*
X03153*
X03158Y03525*
Y0351*
Y0352D02*
X03168Y0353D01*
Y0356D02*
Y0354D01*
X03148Y0356*
X03143*
X03138Y03555*
Y03545*
X03143Y0354*
Y0357D02*
X03138Y03575D01*
Y03585*
X03143Y0359*
X03163*
X03168Y03585*
Y03575*
X03163Y0357*
X03143*
X01982Y02632D02*
Y02662D01*
X01997*
X02002Y02657*
Y02647*
X01997Y02642*
X01982*
X01992D02*
X02002Y02632D01*
X02032D02*
X02012D01*
X02032Y02652*
Y02657*
X02027Y02662*
X02017*
X02012Y02657*
X02062Y02632D02*
X02042D01*
X02062Y02652*
Y02657*
X02057Y02662*
X02047*
X02042Y02657*
X02468Y0054D02*
X02438D01*
Y00555*
X02443Y0056*
X02453*
X02458Y00555*
Y0054*
Y0055D02*
X02468Y0056D01*
Y0059D02*
Y0057D01*
X02448Y0059*
X02443*
X02438Y00585*
Y00575*
X02443Y0057*
Y006D02*
X02438Y00605D01*
Y00615*
X02443Y0062*
X02448*
X02453Y00615*
Y0061*
Y00615*
X02458Y0062*
X02463*
X02468Y00615*
Y00605*
X02463Y006*
X03016Y00537D02*
X02986D01*
Y00552*
X02991Y00557*
X03001*
X03006Y00552*
Y00537*
Y00547D02*
X03016Y00557D01*
Y00587D02*
Y00567D01*
X02996Y00587*
X02991*
X02986Y00582*
Y00572*
X02991Y00567*
X03016Y00612D02*
X02986D01*
X03001Y00597*
Y00617*
X03631Y0389D02*
Y0392D01*
X03646*
X03651Y03915*
Y03905*
X03646Y039*
X03631*
X03641D02*
X03651Y0389D01*
X03681D02*
X03661D01*
X03681Y0391*
Y03915*
X03676Y0392*
X03666*
X03661Y03915*
X03711Y0392D02*
X03691D01*
Y03905*
X03701Y0391*
X03706*
X03711Y03905*
Y03895*
X03706Y0389*
X03696*
X03691Y03895*
X04206Y03678D02*
Y03708D01*
X04221*
X04226Y03703*
Y03693*
X04221Y03688*
X04206*
X04216D02*
X04226Y03678D01*
X04256D02*
X04236D01*
X04256Y03698*
Y03703*
X04251Y03708*
X04241*
X04236Y03703*
X04266Y03708D02*
X04286D01*
Y03703*
X04266Y03683*
Y03678*
X00588Y03998D02*
X00558D01*
Y04013*
X00563Y04018*
X00573*
X00578Y04013*
Y03998*
Y04008D02*
X00588Y04018D01*
Y04048D02*
Y04028D01*
X00568Y04048*
X00563*
X00558Y04043*
Y04033*
X00563Y04028*
Y04058D02*
X00558Y04063D01*
Y04073*
X00563Y04078*
X00568*
X00573Y04073*
X00578Y04078*
X00583*
X00588Y04073*
Y04063*
X00583Y04058*
X00578*
X00573Y04063*
X00568Y04058*
X00563*
X00573Y04063D02*
Y04073D01*
X00789Y03998D02*
X00759D01*
Y04013*
X00764Y04018*
X00774*
X00779Y04013*
Y03998*
Y04008D02*
X00789Y04018D01*
Y04048D02*
Y04028D01*
X00769Y04048*
X00764*
X00759Y04043*
Y04033*
X00764Y04028*
X00784Y04058D02*
X00789Y04063D01*
Y04073*
X00784Y04078*
X00764*
X00759Y04073*
Y04063*
X00764Y04058*
X00769*
X00774Y04063*
Y04078*
X00993Y04004D02*
X00963D01*
Y04019*
X00968Y04024*
X00978*
X00983Y04019*
Y04004*
Y04014D02*
X00993Y04024D01*
X00968Y04034D02*
X00963Y04039D01*
Y04049*
X00968Y04054*
X00973*
X00978Y04049*
Y04044*
Y04049*
X00983Y04054*
X00988*
X00993Y04049*
Y04039*
X00988Y04034*
X00968Y04064D02*
X00963Y04069D01*
Y04079*
X00968Y04084*
X00988*
X00993Y04079*
Y04069*
X00988Y04064*
X00968*
X01198Y04013D02*
X01168D01*
Y04028*
X01173Y04033*
X01183*
X01188Y04028*
Y04013*
Y04023D02*
X01198Y04033D01*
X01173Y04043D02*
X01168Y04048D01*
Y04058*
X01173Y04063*
X01178*
X01183Y04058*
Y04053*
Y04058*
X01188Y04063*
X01193*
X01198Y04058*
Y04048*
X01193Y04043*
X01198Y04073D02*
Y04083D01*
Y04078*
X01168*
X01173Y04073*
X04639Y04263D02*
Y04293D01*
X04654*
X04659Y04288*
Y04278*
X04654Y04273*
X04639*
X04649D02*
X04659Y04263D01*
X04669Y04288D02*
X04674Y04293D01*
X04684*
X04689Y04288*
Y04283*
X04684Y04278*
X04679*
X04684*
X04689Y04273*
Y04268*
X04684Y04263*
X04674*
X04669Y04268*
X04719Y04263D02*
X04699D01*
X04719Y04283*
Y04288*
X04714Y04293*
X04704*
X04699Y04288*
X05199Y04263D02*
Y04293D01*
X05214*
X05219Y04288*
Y04278*
X05214Y04273*
X05199*
X05209D02*
X05219Y04263D01*
X05229Y04288D02*
X05234Y04293D01*
X05244*
X05249Y04288*
Y04283*
X05244Y04278*
X05239*
X05244*
X05249Y04273*
Y04268*
X05244Y04263*
X05234*
X05229Y04268*
X05259Y04288D02*
X05264Y04293D01*
X05274*
X05279Y04288*
Y04283*
X05274Y04278*
X05269*
X05274*
X05279Y04273*
Y04268*
X05274Y04263*
X05264*
X05259Y04268*
X04644Y04058D02*
Y04088D01*
X04659*
X04664Y04083*
Y04073*
X04659Y04068*
X04644*
X04654D02*
X04664Y04058D01*
X04674Y04083D02*
X04679Y04088D01*
X04689*
X04694Y04083*
Y04078*
X04689Y04073*
X04684*
X04689*
X04694Y04068*
Y04063*
X04689Y04058*
X04679*
X04674Y04063*
X04719Y04058D02*
Y04088D01*
X04704Y04073*
X04724*
X05101Y04094D02*
Y04124D01*
X05116*
X05121Y04119*
Y04109*
X05116Y04104*
X05101*
X05111D02*
X05121Y04094D01*
X05131Y04119D02*
X05136Y04124D01*
X05146*
X05151Y04119*
Y04114*
X05146Y04109*
X05141*
X05146*
X05151Y04104*
Y04099*
X05146Y04094*
X05136*
X05131Y04099*
X05181Y04124D02*
X05161D01*
Y04109*
X05171Y04114*
X05176*
X05181Y04109*
Y04099*
X05176Y04094*
X05166*
X05161Y04099*
X04426Y04322D02*
X04421Y04327D01*
X04411*
X04406Y04322*
Y04317*
X04411Y04312*
X04421*
X04426Y04307*
Y04302*
X04421Y04297*
X04411*
X04406Y04302*
X04456Y04327D02*
X04436D01*
Y04312*
X04446Y04317*
X04451*
X04456Y04312*
Y04302*
X04451Y04297*
X04441*
X04436Y04302*
X06561Y02106D02*
Y02081D01*
X06566Y02076*
X06576*
X06581Y02081*
Y02106*
X06591Y02076D02*
X06601D01*
X06596*
Y02106*
X06591Y02101*
X03841Y03633D02*
Y03608D01*
X03846Y03603*
X03856*
X03861Y03608*
Y03633*
X03891D02*
X03881Y03628D01*
X03871Y03618*
Y03608*
X03876Y03603*
X03886*
X03891Y03608*
Y03613*
X03886Y03618*
X03871*
X02388Y03741D02*
Y03716D01*
X02393Y03711*
X02403*
X02408Y03716*
Y03741*
X02418Y03716D02*
X02423Y03711D01*
X02433*
X02438Y03716*
Y03736*
X02433Y03741*
X02423*
X02418Y03736*
Y03731*
X02423Y03726*
X02438*
X06134Y02525D02*
X06104D01*
Y0254*
X06109Y02545*
X06119*
X06124Y0254*
Y02525*
Y02535D02*
X06134Y02545D01*
X06104Y02575D02*
Y02555D01*
X06119*
X06114Y02565*
Y0257*
X06119Y02575*
X06129*
X06134Y0257*
Y0256*
X06129Y02555*
X01895Y04167D02*
Y04197D01*
X0191*
X01915Y04192*
Y04182*
X0191Y04177*
X01895*
X01905D02*
X01915Y04167D01*
X0194D02*
Y04197D01*
X01925Y04182*
X01945*
X01955Y04192D02*
X0196Y04197D01*
X0197*
X01975Y04192*
Y04187*
X0197Y04182*
X01965*
X0197*
X01975Y04177*
Y04172*
X0197Y04167*
X0196*
X01955Y04172*
X01525Y04279D02*
X0152Y04284D01*
X0151*
X01505Y04279*
Y04259*
X0151Y04254*
X0152*
X01525Y04259*
X01535D02*
X0154Y04254D01*
X0155*
X01555Y04259*
Y04279*
X0155Y04284*
X0154*
X01535Y04279*
Y04274*
X0154Y04269*
X01555*
X01585Y04254D02*
X01565D01*
X01585Y04274*
Y04279*
X0158Y04284*
X0157*
X01565Y04279*
X0194Y04243D02*
X01935Y04238D01*
Y04228*
X0194Y04223*
X0196*
X01965Y04228*
Y04238*
X0196Y04243*
Y04253D02*
X01965Y04258D01*
Y04268*
X0196Y04273*
X0194*
X01935Y04268*
Y04258*
X0194Y04253*
X01945*
X0195Y04258*
Y04273*
X01965Y04283D02*
Y04293D01*
Y04288*
X01935*
X0194Y04283*
X06605Y03399D02*
X066Y03404D01*
X0659*
X06585Y03399*
Y03379*
X0659Y03374*
X066*
X06605Y03379*
X06615Y03399D02*
X0662Y03404D01*
X0663*
X06635Y03399*
Y03394*
X0663Y03389*
X06635Y03384*
Y03379*
X0663Y03374*
X0662*
X06615Y03379*
Y03384*
X0662Y03389*
X06615Y03394*
Y03399*
X0662Y03389D02*
X0663D01*
X06665Y03404D02*
X06655Y03399D01*
X06645Y03389*
Y03379*
X0665Y03374*
X0666*
X06665Y03379*
Y03384*
X0666Y03389*
X06645*
X06654Y03076D02*
X06649Y03081D01*
X06639*
X06634Y03076*
Y03056*
X06639Y03051*
X06649*
X06654Y03056*
X06664Y03076D02*
X06669Y03081D01*
X06679*
X06684Y03076*
Y03071*
X06679Y03066*
X06684Y03061*
Y03056*
X06679Y03051*
X06669*
X06664Y03056*
Y03061*
X06669Y03066*
X06664Y03071*
Y03076*
X06669Y03066D02*
X06679D01*
X06714Y03081D02*
X06694D01*
Y03066*
X06704Y03071*
X06709*
X06714Y03066*
Y03056*
X06709Y03051*
X06699*
X06694Y03056*
X042Y03341D02*
X04195Y03346D01*
X04185*
X0418Y03341*
Y03321*
X04185Y03316*
X04195*
X042Y03321*
X0421Y03341D02*
X04215Y03346D01*
X04225*
X0423Y03341*
Y03336*
X04225Y03331*
X0423Y03326*
Y03321*
X04225Y03316*
X04215*
X0421Y03321*
Y03326*
X04215Y03331*
X0421Y03336*
Y03341*
X04215Y03331D02*
X04225D01*
X04255Y03316D02*
Y03346D01*
X0424Y03331*
X0426*
X04487Y03185D02*
X04482Y0318D01*
Y0317*
X04487Y03165*
X04507*
X04512Y0317*
Y0318*
X04507Y03185*
X04487Y03195D02*
X04482Y032D01*
Y0321*
X04487Y03215*
X04492*
X04497Y0321*
X04502Y03215*
X04507*
X04512Y0321*
Y032*
X04507Y03195*
X04502*
X04497Y032*
X04492Y03195*
X04487*
X04497Y032D02*
Y0321D01*
X04487Y03225D02*
X04482Y0323D01*
Y0324*
X04487Y03245*
X04492*
X04497Y0324*
Y03235*
Y0324*
X04502Y03245*
X04507*
X04512Y0324*
Y0323*
X04507Y03225*
X04438Y03225D02*
X04433Y0322D01*
Y0321*
X04438Y03205*
X04458*
X04463Y0321*
Y0322*
X04458Y03225*
X04438Y03235D02*
X04433Y0324D01*
Y0325*
X04438Y03255*
X04443*
X04448Y0325*
X04453Y03255*
X04458*
X04463Y0325*
Y0324*
X04458Y03235*
X04453*
X04448Y0324*
X04443Y03235*
X04438*
X04448Y0324D02*
Y0325D01*
X04463Y03285D02*
Y03265D01*
X04443Y03285*
X04438*
X04433Y0328*
Y0327*
X04438Y03265*
X04389Y0323D02*
X04384Y03225D01*
Y03215*
X04389Y0321*
X04409*
X04414Y03215*
Y03225*
X04409Y0323*
X04389Y0324D02*
X04384Y03245D01*
Y03255*
X04389Y0326*
X04394*
X04399Y03255*
X04404Y0326*
X04409*
X04414Y03255*
Y03245*
X04409Y0324*
X04404*
X04399Y03245*
X04394Y0324*
X04389*
X04399Y03245D02*
Y03255D01*
X04414Y0327D02*
Y0328D01*
Y03275*
X04384*
X04389Y0327*
X04339Y0323D02*
X04334Y03225D01*
Y03215*
X04339Y0321*
X04359*
X04364Y03215*
Y03225*
X04359Y0323*
X04339Y0324D02*
X04334Y03245D01*
Y03255*
X04339Y0326*
X04344*
X04349Y03255*
X04354Y0326*
X04359*
X04364Y03255*
Y03245*
X04359Y0324*
X04354*
X04349Y03245*
X04344Y0324*
X04339*
X04349Y03245D02*
Y03255D01*
X04339Y0327D02*
X04334Y03275D01*
Y03285*
X04339Y0329*
X04359*
X04364Y03285*
Y03275*
X04359Y0327*
X04339*
X04125Y03207D02*
X0412Y03202D01*
Y03192*
X04125Y03187*
X04145*
X0415Y03192*
Y03202*
X04145Y03207*
X0412Y03217D02*
Y03237D01*
X04125*
X04145Y03217*
X0415*
X04145Y03247D02*
X0415Y03252D01*
Y03262*
X04145Y03267*
X04125*
X0412Y03262*
Y03252*
X04125Y03247*
X0413*
X04135Y03252*
Y03267*
X04069Y03207D02*
X04064Y03202D01*
Y03192*
X04069Y03187*
X04089*
X04094Y03192*
Y03202*
X04089Y03207*
X04064Y03217D02*
Y03237D01*
X04069*
X04089Y03217*
X04094*
X04069Y03247D02*
X04064Y03252D01*
Y03262*
X04069Y03267*
X04074*
X04079Y03262*
X04084Y03267*
X04089*
X04094Y03262*
Y03252*
X04089Y03247*
X04084*
X04079Y03252*
X04074Y03247*
X04069*
X04079Y03252D02*
Y03262D01*
X04001Y02936D02*
X03996Y02941D01*
X03986*
X03981Y02936*
Y02916*
X03986Y02911*
X03996*
X04001Y02916*
X04011Y02941D02*
X04031D01*
Y02936*
X04011Y02916*
Y02911*
X04061Y02941D02*
X04041D01*
Y02926*
X04051Y02931*
X04056*
X04061Y02926*
Y02916*
X04056Y02911*
X04046*
X04041Y02916*
X03787Y02818D02*
X03782Y02823D01*
X03772*
X03767Y02818*
Y02798*
X03772Y02793*
X03782*
X03787Y02798*
X03797Y02823D02*
X03817D01*
Y02818*
X03797Y02798*
Y02793*
X03842D02*
Y02823D01*
X03827Y02808*
X03847*
X04235Y02915D02*
X0423Y0291D01*
Y029*
X04235Y02895*
X04255*
X0426Y029*
Y0291*
X04255Y02915*
X0423Y02925D02*
Y02945D01*
X04235*
X04255Y02925*
X0426*
X04235Y02955D02*
X0423Y0296D01*
Y0297*
X04235Y02975*
X0424*
X04245Y0297*
Y02965*
Y0297*
X0425Y02975*
X04255*
X0426Y0297*
Y0296*
X04255Y02955*
X01345Y04326D02*
X01335D01*
X0134*
Y04301*
X01335Y04296*
X0133*
X01325Y04301*
X01355Y04296D02*
Y04326D01*
X0137*
X01375Y04321*
Y04311*
X0137Y04306*
X01355*
X01385Y04296D02*
X01395D01*
X0139*
Y04326*
X01385Y04321*
G54D25*
X06557Y03151D03*
M02*